FILE_TYPE = MACRO_DRAWING;
SET COLOR_WIRE YELLOW;
SET COLOR_PROP ORANGE;
SET COLOR_DOT WHITE;
SET COLOR_ARC YELLOW;
SET COLOR_BODY GREEN;
SET COLOR_NOTE PURPLE;
SET PROP_DISPLAY VALUE;
SET PAGE_NUMBER P253;
FORCEADD UNIVERSAL_GND..1
(-4200 -2850);
FORCEPROP 3 LASTPIN (-4200 -2800) SIG_NAME GND\g
J 0
(-4190 -2790);
DISPLAY 0.659574 (-4190 -2790);
PAINT MONO (-4190 -2790);
DISPLAY INVISIBLE (-4190 -2790);
FORCEPROP 1 LAST HDL_POWER GND
J 1
(-4175 -2925);
DISPLAY 0.872340 (-4175 -2925);
PAINT GREEN (-4175 -2925);
DISPLAY INVISIBLE (-4175 -2925);
FORCEPROP 2 LAST CDS_LIB logical_power
J 0
(-4200 -2850);
PAINT MONO (-4200 -2850);
DISPLAY INVISIBLE (-4200 -2850);
FORCEPROP 1 LAST PATH I1
J 0
(-4125 -2850);
DISPLAY 0.872340 (-4125 -2850);
PAINT AQUA (-4125 -2850);
DISPLAY INVISIBLE (-4125 -2850);
FORCEADD UNIVERSAL_GND..1
(-3800 -1875);
FORCEPROP 3 LASTPIN (-3800 -1825) SIG_NAME GND\g
J 0
(-3790 -1815);
DISPLAY 0.659574 (-3790 -1815);
PAINT MONO (-3790 -1815);
DISPLAY INVISIBLE (-3790 -1815);
FORCEPROP 1 LAST HDL_POWER GND
J 1
(-3775 -1950);
DISPLAY 0.872340 (-3775 -1950);
PAINT GREEN (-3775 -1950);
DISPLAY INVISIBLE (-3775 -1950);
FORCEPROP 2 LAST CDS_LIB logical_power
J 0
(-3800 -1875);
PAINT MONO (-3800 -1875);
DISPLAY INVISIBLE (-3800 -1875);
FORCEPROP 1 LAST PATH I10
J 0
(-3725 -1875);
DISPLAY 0.872340 (-3725 -1875);
PAINT AQUA (-3725 -1875);
DISPLAY INVISIBLE (-3725 -1875);
FORCEADD Q_CAP..2
(-3475 -2325);
FORCEPROP 1 LAST PART_NUMBER CH4104K1B00
J 1
(-3200 -2275);
DISPLAY 0.617021 (-3200 -2275);
PAINT BLUE (-3200 -2275);
DISPLAY INVISIBLE (-3200 -2275);
FORCEPROP 1 LAST PACK_TYPE 0402
J 1
(-2950 -2325);
DISPLAY 0.617021 (-2950 -2325);
PAINT SKYBLUE (-2950 -2325);
FORCEPROP 1 LAST MATERIAL X7R
J 0
(-3025 -2275);
DISPLAY 0.617021 (-3025 -2275);
PAINT SKYBLUE (-3025 -2275);
FORCEPROP 1 LAST TOLERANCE 10%
J 2
(-2825 -2275);
DISPLAY 0.617021 (-2825 -2275);
PAINT SKYBLUE (-2825 -2275);
FORCEPROP 1 LAST VOLTAGE 25V
J 0
(-3150 -2325);
DISPLAY 0.617021 (-3150 -2325);
PAINT SKYBLUE (-3150 -2325);
FORCEPROP 1 LAST VALUE 0.1UF
J 2
(-3175 -2325);
DISPLAY 0.617021 (-3175 -2325);
PAINT SKYBLUE (-3175 -2325);
FORCEPROP 1 LAST LOCATION PC1355
J 1
(-3675 -2325);
DISPLAY 0.617021 (-3675 -2325);
PAINT AQUA (-3675 -2325);
FORCEPROP 1 LASTPIN (-3575 -2325) $PN 1
J 0
(-3585 -2310);
DISPLAY 0.617021 (-3585 -2310);
FORCEPROP 1 LASTPIN (-3375 -2325) $PN 2
J 0
(-3390 -2310);
DISPLAY 0.617021 (-3390 -2310);
FORCEPROP 2 LAST CDS_LIB pure_quanta
J 0
(-3475 -2325);
PAINT MONO (-3475 -2325);
DISPLAY INVISIBLE (-3475 -2325);
FORCEPROP 1 LAST PATH I11
J 0
(-3475 -2125);
DISPLAY 0.978723 (-3475 -2125);
PAINT WHITE (-3475 -2125);
DISPLAY INVISIBLE (-3475 -2125);
FORCEPROP 2 LAST $SEC 1
J 0
(-3475 -2075);
DISPLAY 0.680851 (-3475 -2075);
PAINT MONO (-3475 -2075);
DISPLAY INVISIBLE (-3475 -2075);
FORCEPROP 2 LAST CDS_SEC 1
J 0
(-3475 -2075);
DISPLAY 1.021277 (-3475 -2075);
DISPLAY INVISIBLE (-3475 -2075);
FORCEADD Q_RES..2
(-3800 -1125);
FORCEPROP 1 LAST PART_NUMBER CS-2202FB01
J 0
(-3760 -1250);
DISPLAY 0.617021 (-3760 -1250);
PAINT BLUE (-3760 -1250);
DISPLAY INVISIBLE (-3760 -1250);
FORCEPROP 1 LAST PACK_TYPE 0402LF
J 0
(-3760 -1300);
DISPLAY 0.617021 (-3760 -1300);
PAINT SKYBLUE (-3760 -1300);
FORCEPROP 1 LAST VALUE 2.2
J 0
(-3755 -1050);
DISPLAY 0.617021 (-3755 -1050);
PAINT SKYBLUE (-3755 -1050);
FORCEPROP 1 LAST TOLERANCE 1%
J 0
(-3755 -1100);
DISPLAY 0.617021 (-3755 -1100);
PAINT SKYBLUE (-3755 -1100);
FORCEPROP 1 LAST MATERIAL CHIP
J 0
(-3760 -1200);
DISPLAY 0.617021 (-3760 -1200);
PAINT SKYBLUE (-3760 -1200);
FORCEPROP 1 LAST WATTAGE 1/16W
J 0
(-3760 -1150);
DISPLAY 0.617021 (-3760 -1150);
PAINT SKYBLUE (-3760 -1150);
FORCEPROP 1 LAST LOCATION PR152
J 0
(-3755 -1000);
DISPLAY 0.617021 (-3755 -1000);
PAINT AQUA (-3755 -1000);
FORCEPROP 1 LASTPIN (-3800 -1025) $PN 1
J 0
(-3795 -1063);
DISPLAY 0.617021 (-3795 -1063);
PAINT MONO (-3795 -1063);
FORCEPROP 1 LASTPIN (-3800 -1225) $PN 2
J 0
(-3795 -1215);
DISPLAY 0.617021 (-3795 -1215);
PAINT MONO (-3795 -1215);
FORCEPROP 2 LAST CDS_LIB pure_quanta
J 0
(-3800 -1125);
DISPLAY INVISIBLE (-3800 -1125);
FORCEPROP 1 LAST PATH I12
J 0
(-3750 -950);
DISPLAY 0.978723 (-3750 -950);
PAINT WHITE (-3750 -950);
DISPLAY INVISIBLE (-3750 -950);
FORCEPROP 1 LAST LOCATION PR152
J 0
(-3750 -950);
DISPLAY 1.021277 (-3750 -950);
PAINT AQUA (-3750 -950);
DISPLAY INVISIBLE (-3750 -950);
FORCEPROP 0 LAST $SEC 1
J 0
(-3750 -950);
DISPLAY 0.680851 (-3750 -950);
PAINT MONO (-3750 -950);
DISPLAY INVISIBLE (-3750 -950);
FORCEPROP 0 LAST CDS_SEC 1
J 0
(-3750 -950);
DISPLAY 1.021277 (-3750 -950);
DISPLAY INVISIBLE (-3750 -950);
FORCEADD VCC15..1
(-3800 -800);
FORCEPROP 3 LASTPIN (-3800 -850) SIG_NAME PVCCIN_CPU0_PVCC\g
J 0
(-3790 -840);
DISPLAY 0.659574 (-3790 -840);
PAINT MONO (-3790 -840);
DISPLAY INVISIBLE (-3790 -840);
FORCEPROP 1 LAST HDL_POWER PVCCIN_CPU0_PVCC
J 1
(-3800 -750);
DISPLAY 0.617021 (-3800 -750);
PAINT GREEN (-3800 -750);
FORCEPROP 2 LAST CDS_LIB logical_power
J 0
(-3800 -800);
DISPLAY INVISIBLE (-3800 -800);
FORCEPROP 1 LAST PATH I13
J 0
(-3750 -775);
DISPLAY 0.872340 (-3750 -775);
PAINT AQUA (-3750 -775);
DISPLAY INVISIBLE (-3750 -775);
FORCEADD UNIVERSAL_GND..1
(-3375 -1350);
FORCEPROP 3 LASTPIN (-3375 -1300) SIG_NAME GND\g
J 0
(-3365 -1290);
DISPLAY 0.659574 (-3365 -1290);
PAINT MONO (-3365 -1290);
DISPLAY INVISIBLE (-3365 -1290);
FORCEPROP 1 LAST HDL_POWER GND
J 1
(-3350 -1425);
DISPLAY 0.872340 (-3350 -1425);
PAINT GREEN (-3350 -1425);
DISPLAY INVISIBLE (-3350 -1425);
FORCEPROP 2 LAST CDS_LIB logical_power
J 0
(-3375 -1350);
PAINT MONO (-3375 -1350);
DISPLAY INVISIBLE (-3375 -1350);
FORCEPROP 1 LAST PATH I14
J 0
(-3300 -1350);
DISPLAY 0.872340 (-3300 -1350);
PAINT AQUA (-3300 -1350);
DISPLAY INVISIBLE (-3300 -1350);
FORCEADD Q_CAP..1
(-3375 -1125);
FORCEPROP 1 LAST PART_NUMBER CH5222KEB01
J 0
(-3325 -1250);
DISPLAY 0.617021 (-3325 -1250);
PAINT BLUE (-3325 -1250);
DISPLAY INVISIBLE (-3325 -1250);
FORCEPROP 1 LAST PACK_TYPE C0402
J 0
(-3325 -1300);
DISPLAY 0.617021 (-3325 -1300);
PAINT SKYBLUE (-3325 -1300);
FORCEPROP 1 LAST VOLTAGE 10V
J 0
(-3325 -1100);
DISPLAY 0.617021 (-3325 -1100);
PAINT SKYBLUE (-3325 -1100);
FORCEPROP 1 LAST VALUE 2.2UF
J 0
(-3325 -1050);
DISPLAY 0.617021 (-3325 -1050);
PAINT SKYBLUE (-3325 -1050);
FORCEPROP 1 LAST TOLERANCE 10%
J 0
(-3325 -1150);
DISPLAY 0.617021 (-3325 -1150);
PAINT SKYBLUE (-3325 -1150);
FORCEPROP 1 LAST MATERIAL X6S
J 0
(-3325 -1200);
DISPLAY 0.617021 (-3325 -1200);
PAINT SKYBLUE (-3325 -1200);
FORCEPROP 1 LAST LOCATION PC294_P0_2
J 0
(-3325 -1000);
DISPLAY 0.617021 (-3325 -1000);
PAINT AQUA (-3325 -1000);
FORCEPROP 1 LASTPIN (-3375 -1025) $PN 1
J 0
(-3365 -1045);
DISPLAY 0.617021 (-3365 -1045);
PAINT MONO (-3365 -1045);
FORCEPROP 1 LASTPIN (-3375 -1225) $PN 2
J 0
(-3365 -1245);
DISPLAY 0.617021 (-3365 -1245);
PAINT MONO (-3365 -1245);
FORCEPROP 2 LAST CDS_LIB pure_quanta
J 0
(-3375 -1125);
DISPLAY INVISIBLE (-3375 -1125);
FORCEPROP 1 LAST PATH I15
J 0
(-3325 -975);
DISPLAY 0.978723 (-3325 -975);
PAINT WHITE (-3325 -975);
DISPLAY INVISIBLE (-3325 -975);
FORCEPROP 1 LAST LOCATION PC294_P0_2
J 0
(-3325 -950);
DISPLAY 1.021277 (-3325 -950);
PAINT AQUA (-3325 -950);
DISPLAY INVISIBLE (-3325 -950);
FORCEPROP 0 LAST $SEC 1
J 0
(-3325 -950);
DISPLAY 0.680851 (-3325 -950);
PAINT MONO (-3325 -950);
DISPLAY INVISIBLE (-3325 -950);
FORCEPROP 0 LAST CDS_SEC 1
J 0
(-3325 -950);
DISPLAY 1.021277 (-3325 -950);
DISPLAY INVISIBLE (-3325 -950);
FORCEADD UNIVERSAL_GND..1
(-1625 -2850);
FORCEPROP 3 LASTPIN (-1625 -2800) SIG_NAME GND\g
J 0
(-1615 -2790);
DISPLAY 0.659574 (-1615 -2790);
PAINT MONO (-1615 -2790);
DISPLAY INVISIBLE (-1615 -2790);
FORCEPROP 1 LAST HDL_POWER GND
J 1
(-1600 -2925);
DISPLAY 0.872340 (-1600 -2925);
PAINT GREEN (-1600 -2925);
DISPLAY INVISIBLE (-1600 -2925);
FORCEPROP 2 LAST CDS_LIB logical_power
J 0
(-1625 -2850);
PAINT MONO (-1625 -2850);
DISPLAY INVISIBLE (-1625 -2850);
FORCEPROP 1 LAST PATH I16
J 0
(-1550 -2850);
DISPLAY 0.872340 (-1550 -2850);
PAINT AQUA (-1550 -2850);
DISPLAY INVISIBLE (-1550 -2850);
FORCEADD OFFPAGE..6
(-750 -2375);
FORCEPROP 2 LAST $XR0 267 
J 0
(-1030 -2375);
DISPLAY 0.638298 (-1030 -2375);
PAINT MONO (-1030 -2375);
FORCEPROP 1 LAST COMMENT_BODY TRUE
J 0
(-650 -2450);
DISPLAY 0.872340 (-650 -2450);
PAINT GREEN (-650 -2450);
DISPLAY INVISIBLE (-650 -2450);
FORCEPROP 1 LAST OFFPAGE TRUE
J 0
(-425 -2500);
DISPLAY 0.872340 (-425 -2500);
DISPLAY INVISIBLE (-425 -2500);
FORCEPROP 2 LAST CDS_LIB standard
J 0
(-750 -2375);
DISPLAY INVISIBLE (-750 -2375);
FORCEPROP 2 LAST PATH I17
J 0
(-1025 -2325);
DISPLAY 1.021277 (-1025 -2325);
DISPLAY INVISIBLE (-1025 -2325);
FORCEADD Q_RES..1
(-1025 -1675);
FORCEPROP 1 LAST PART_NUMBER CS-3302FB01
J 0
(-1125 -1625);
DISPLAY 0.617021 (-1125 -1625);
PAINT BLUE (-1125 -1625);
DISPLAY INVISIBLE (-1125 -1625);
FORCEPROP 1 LAST TOLERANCE 1%
J 0
(-775 -1675);
DISPLAY 0.617021 (-775 -1675);
PAINT SKYBLUE (-775 -1675);
FORCEPROP 1 LAST VALUE 3.3
J 2
(-800 -1675);
DISPLAY 0.617021 (-800 -1675);
PAINT SKYBLUE (-800 -1675);
FORCEPROP 1 LAST WATTAGE 1/16W
J 2
(-775 -1600);
DISPLAY 0.617021 (-775 -1600);
PAINT SKYBLUE (-775 -1600);
FORCEPROP 1 LAST MATERIAL CHIP
J 0
(-1125 -1575);
DISPLAY 0.617021 (-1125 -1575);
PAINT SKYBLUE (-1125 -1575);
FORCEPROP 1 LAST PACK_TYPE 0402LF
J 0
(-1125 -1600);
DISPLAY 0.617021 (-1125 -1600);
PAINT SKYBLUE (-1125 -1600);
FORCEPROP 1 LAST LOCATION PR1786
J 0
(-1275 -1675);
DISPLAY 0.617021 (-1275 -1675);
PAINT AQUA (-1275 -1675);
FORCEPROP 1 LASTPIN (-1125 -1675) $PN 1
J 0
(-1113 -1663);
DISPLAY 0.617021 (-1113 -1663);
FORCEPROP 1 LASTPIN (-925 -1675) $PN 2
J 0
(-963 -1663);
DISPLAY 0.617021 (-963 -1663);
FORCEPROP 2 LAST CDS_LIB pure_quanta
J 0
(-1025 -1675);
PAINT MONO (-1025 -1675);
DISPLAY INVISIBLE (-1025 -1675);
FORCEPROP 1 LAST PATH I18
J 0
(-1075 -1525);
DISPLAY 0.978723 (-1075 -1525);
PAINT WHITE (-1075 -1525);
DISPLAY INVISIBLE (-1075 -1525);
FORCEPROP 2 LAST $SEC 1
J 0
(-1075 -1475);
DISPLAY 0.680851 (-1075 -1475);
PAINT MONO (-1075 -1475);
DISPLAY INVISIBLE (-1075 -1475);
FORCEPROP 2 LAST CDS_SEC 1
J 0
(-1075 -1475);
DISPLAY 1.021277 (-1075 -1475);
DISPLAY INVISIBLE (-1075 -1475);
FORCEADD Q_CAP..1
(-1475 -1225);
FORCEPROP 1 LAST PART_NUMBER TMP_QCH2336K1B12
J 0
(-1425 -1375);
DISPLAY 0.617021 (-1425 -1375);
PAINT BLUE (-1425 -1375);
DISPLAY INVISIBLE (-1425 -1375);
FORCEPROP 1 LAST TOLERANCE 10%
J 0
(-1425 -1225);
DISPLAY 0.617021 (-1425 -1225);
PAINT SKYBLUE (-1425 -1225);
FORCEPROP 1 LAST MATERIAL X7R
J 0
(-1425 -1275);
DISPLAY 0.617021 (-1425 -1275);
PAINT SKYBLUE (-1425 -1275);
FORCEPROP 1 LAST PACK_TYPE 0402
J 0
(-1425 -1325);
DISPLAY 0.617021 (-1425 -1325);
PAINT SKYBLUE (-1425 -1325);
FORCEPROP 1 LAST VALUE 3300PF
J 0
(-1425 -1125);
DISPLAY 0.617021 (-1425 -1125);
PAINT SKYBLUE (-1425 -1125);
FORCEPROP 1 LAST VOLTAGE 50V
J 0
(-1425 -1175);
DISPLAY 0.617021 (-1425 -1175);
PAINT SKYBLUE (-1425 -1175);
FORCEPROP 1 LAST LOCATION PC296_P0_2
J 0
(-1425 -1075);
DISPLAY 0.617021 (-1425 -1075);
PAINT AQUA (-1425 -1075);
FORCEPROP 1 LASTPIN (-1475 -1125) $PN 1
J 0
(-1465 -1145);
DISPLAY 0.617021 (-1465 -1145);
PAINT MONO (-1465 -1145);
FORCEPROP 1 LASTPIN (-1475 -1325) $PN 2
J 0
(-1465 -1345);
DISPLAY 0.617021 (-1465 -1345);
PAINT MONO (-1465 -1345);
FORCEPROP 2 LAST CDS_LIB pure_quanta
J 0
(-1475 -1225);
DISPLAY INVISIBLE (-1475 -1225);
FORCEPROP 1 LAST PATH I19
J 0
(-1425 -1075);
DISPLAY 0.978723 (-1425 -1075);
PAINT WHITE (-1425 -1075);
DISPLAY INVISIBLE (-1425 -1075);
FORCEPROP 1 LAST LOCATION PC296_P0_2
J 0
(-1425 -1025);
DISPLAY 1.021277 (-1425 -1025);
PAINT AQUA (-1425 -1025);
DISPLAY INVISIBLE (-1425 -1025);
FORCEPROP 0 LAST $SEC 1
J 0
(-1425 -1025);
DISPLAY 0.680851 (-1425 -1025);
PAINT MONO (-1425 -1025);
DISPLAY INVISIBLE (-1425 -1025);
FORCEPROP 0 LAST CDS_SEC 1
J 0
(-1425 -1025);
DISPLAY 1.021277 (-1425 -1025);
DISPLAY INVISIBLE (-1425 -1025);
FORCEADD Q_RES..2
R 2
(-4200 -2625);
FORCEPROP 1 LAST PART_NUMBER CS28872FB01
J 2
(-4240 -2750);
DISPLAY 0.617021 (-4240 -2750);
PAINT BLUE (-4240 -2750);
DISPLAY INVISIBLE (-4240 -2750);
FORCEPROP 1 LAST PACK_TYPE 0402LF
J 2
(-4240 -2800);
DISPLAY 0.617021 (-4240 -2800);
PAINT SKYBLUE (-4240 -2800);
FORCEPROP 1 LAST VALUE 8.87K
J 2
(-4245 -2550);
DISPLAY 0.617021 (-4245 -2550);
PAINT SKYBLUE (-4245 -2550);
FORCEPROP 1 LAST TOLERANCE 1%
J 2
(-4245 -2600);
DISPLAY 0.617021 (-4245 -2600);
PAINT SKYBLUE (-4245 -2600);
FORCEPROP 1 LAST MATERIAL EMPTY
J 2
(-4240 -2700);
DISPLAY 0.617021 (-4240 -2700);
PAINT RED (-4240 -2700);
FORCEPROP 1 LAST WATTAGE 1/16W
J 2
(-4240 -2650);
DISPLAY 0.617021 (-4240 -2650);
PAINT SKYBLUE (-4240 -2650);
FORCEPROP 1 LAST LOCATION PR150
J 2
(-4245 -2500);
DISPLAY 0.617021 (-4245 -2500);
PAINT AQUA (-4245 -2500);
FORCEPROP 1 LASTPIN (-4200 -2525) $PN 1
J 2
(-4205 -2563);
DISPLAY 0.617021 (-4205 -2563);
PAINT MONO (-4205 -2563);
FORCEPROP 1 LASTPIN (-4200 -2725) $PN 2
J 2
(-4205 -2715);
DISPLAY 0.617021 (-4205 -2715);
PAINT MONO (-4205 -2715);
FORCEPROP 2 LAST CDS_LIB pure_quanta
J 2
(-4200 -2625);
DISPLAY INVISIBLE (-4200 -2625);
FORCEPROP 1 LAST PATH I2
J 2
(-4250 -2450);
DISPLAY 0.978723 (-4250 -2450);
PAINT WHITE (-4250 -2450);
DISPLAY INVISIBLE (-4250 -2450);
FORCEPROP 0 LAST $SEC 1
J 0
(-4225 -2450);
DISPLAY 0.680851 (-4225 -2450);
PAINT MONO (-4225 -2450);
DISPLAY INVISIBLE (-4225 -2450);
FORCEPROP 0 LAST CDS_SEC 1
J 0
(-4225 -2450);
DISPLAY 1.021277 (-4225 -2450);
DISPLAY INVISIBLE (-4225 -2450);
FORCEADD Q_CAP..1
R 2
(-225 -1875);
FORCEPROP 1 LAST PART_NUMBER CH4106K1B01
J 2
(-250 -1925);
DISPLAY 0.617021 (-250 -1925);
PAINT BLUE (-250 -1925);
DISPLAY INVISIBLE (-250 -1925);
FORCEPROP 1 LAST VOLTAGE 50V
J 2
(-275 -1850);
DISPLAY 0.617021 (-275 -1850);
PAINT SKYBLUE (-275 -1850);
FORCEPROP 1 LAST VALUE 100NF
J 2
(-275 -1825);
DISPLAY 0.617021 (-275 -1825);
PAINT SKYBLUE (-275 -1825);
FORCEPROP 1 LAST TOLERANCE 10%
J 2
(-275 -1875);
DISPLAY 0.617021 (-275 -1875);
PAINT SKYBLUE (-275 -1875);
FORCEPROP 1 LAST MATERIAL X7R
J 2
(-275 -1900);
DISPLAY 0.617021 (-275 -1900);
PAINT SKYBLUE (-275 -1900);
FORCEPROP 1 LAST PACK_TYPE C0402
J 2
(-275 -1950);
DISPLAY 0.617021 (-275 -1950);
PAINT SKYBLUE (-275 -1950);
FORCEPROP 1 LAST LOCATION PC300
J 2
(-275 -1800);
DISPLAY 0.617021 (-275 -1800);
PAINT AQUA (-275 -1800);
FORCEPROP 1 LASTPIN (-225 -1775) $PN 1
J 2
(-235 -1795);
DISPLAY 0.617021 (-235 -1795);
FORCEPROP 1 LASTPIN (-225 -1975) $PN 2
J 2
(-235 -1995);
DISPLAY 0.617021 (-235 -1995);
FORCEPROP 2 LAST CDS_LIB pure_quanta
J 2
(-225 -1875);
PAINT MONO (-225 -1875);
DISPLAY INVISIBLE (-225 -1875);
FORCEPROP 1 LAST PATH I20
J 2
(-275 -1725);
DISPLAY 0.978723 (-275 -1725);
PAINT WHITE (-275 -1725);
DISPLAY INVISIBLE (-275 -1725);
FORCEPROP 2 LAST $SEC 1
J 0
(-275 -1675);
DISPLAY 0.680851 (-275 -1675);
PAINT MONO (-275 -1675);
DISPLAY INVISIBLE (-275 -1675);
FORCEPROP 2 LAST CDS_SEC 1
J 0
(-275 -1675);
DISPLAY 1.021277 (-275 -1675);
DISPLAY INVISIBLE (-275 -1675);
FORCEADD Q_INDUCTOR4P_14..1
(250 -2250);
FORCEPROP 1 LAST PART_NUMBER CV+15^0TZ04
J 0
(25 -2090);
DISPLAY 0.617021 (25 -2090);
PAINT BLUE (25 -2090);
DISPLAY INVISIBLE (25 -2090);
FORCEPROP 2 LAST VALUE 150NH
J 0
(25 -1950);
DISPLAY 0.617021 (25 -1950);
PAINT SKYBLUE (25 -1950);
FORCEPROP 1 LAST MATERIAL IND
J 0
(25 -2040);
DISPLAY 0.617021 (25 -2040);
PAINT SKYBLUE (25 -2040);
FORCEPROP 2 LAST PART_TYPE SMLF
J 0
(25 -1900);
DISPLAY 1.021277 (25 -1900);
FORCEPROP 1 LAST LOCATION PL13
J 0
(25 -1995);
DISPLAY 0.617021 (25 -1995);
PAINT AQUA (25 -1995);
FORCEPROP 2 LASTPIN (-150 -2125) $PN 1
J 2
(-160 -2115);
DISPLAY 0.617021 (-160 -2115);
PAINT MONO (-160 -2115);
FORCEPROP 2 LASTPIN (-150 -2375) $PN 2
J 2
(-160 -2365);
DISPLAY 0.617021 (-160 -2365);
PAINT MONO (-160 -2365);
FORCEPROP 2 LASTPIN (650 -2375) $PN 3
J 0
(660 -2365);
DISPLAY 0.617021 (660 -2365);
PAINT MONO (660 -2365);
FORCEPROP 2 LASTPIN (650 -2125) $PN 4
J 0
(660 -2115);
DISPLAY 0.617021 (660 -2115);
PAINT MONO (660 -2115);
FORCEPROP 2 LAST SEC_TYPE 
J 0
(25 -1850);
DISPLAY 1.021277 (25 -1850);
DISPLAY INVISIBLE (25 -1850);
FORCEPROP 2 LAST CDS_LIB pure_quanta
J 0
(250 -2250);
DISPLAY INVISIBLE (250 -2250);
FORCEPROP 1 LAST NEEDS_NO_SIZE TRUE
J 0
(250 -2250);
DISPLAY 0.468085 (250 -2250);
PAINT GREEN (250 -2250);
DISPLAY INVISIBLE (250 -2250);
FORCEPROP 1 LAST PATH I21
J 0
(450 -2095);
DISPLAY 0.723404 (450 -2095);
PAINT GREEN (450 -2095);
DISPLAY INVISIBLE (450 -2095);
FORCEPROP 2 LAST SEC 1
J 0
(25 -1850);
DISPLAY 0.680851 (25 -1850);
PAINT MONO (25 -1850);
DISPLAY INVISIBLE (25 -1850);
FORCEADD Q_CAP..1
(-1075 -1225);
FORCEPROP 1 LAST PART_NUMBER CH5103KEB01
J 0
(-1025 -1375);
DISPLAY 0.617021 (-1025 -1375);
PAINT BLUE (-1025 -1375);
DISPLAY INVISIBLE (-1025 -1375);
FORCEPROP 1 LAST PACK_TYPE C0402
J 0
(-1025 -1325);
DISPLAY 0.617021 (-1025 -1325);
PAINT SKYBLUE (-1025 -1325);
FORCEPROP 1 LAST VOLTAGE 16V
J 0
(-1025 -1175);
DISPLAY 0.617021 (-1025 -1175);
PAINT SKYBLUE (-1025 -1175);
FORCEPROP 1 LAST VALUE 1UF
J 0
(-1025 -1125);
DISPLAY 0.617021 (-1025 -1125);
PAINT SKYBLUE (-1025 -1125);
FORCEPROP 1 LAST TOLERANCE 10%
J 0
(-1025 -1225);
DISPLAY 0.617021 (-1025 -1225);
PAINT SKYBLUE (-1025 -1225);
FORCEPROP 1 LAST MATERIAL X6S
J 0
(-1025 -1275);
DISPLAY 0.617021 (-1025 -1275);
PAINT SKYBLUE (-1025 -1275);
FORCEPROP 1 LAST LOCATION PC298_P0_2
J 0
(-1025 -1075);
DISPLAY 0.617021 (-1025 -1075);
PAINT AQUA (-1025 -1075);
FORCEPROP 1 LASTPIN (-1075 -1125) $PN 1
J 0
(-1065 -1145);
DISPLAY 0.617021 (-1065 -1145);
PAINT MONO (-1065 -1145);
FORCEPROP 1 LASTPIN (-1075 -1325) $PN 2
J 0
(-1065 -1345);
DISPLAY 0.617021 (-1065 -1345);
PAINT MONO (-1065 -1345);
FORCEPROP 2 LAST CDS_LIB pure_quanta
J 0
(-1075 -1225);
DISPLAY INVISIBLE (-1075 -1225);
FORCEPROP 1 LAST PATH I22
J 0
(-1025 -1075);
DISPLAY 0.978723 (-1025 -1075);
PAINT WHITE (-1025 -1075);
DISPLAY INVISIBLE (-1025 -1075);
FORCEPROP 1 LAST LOCATION PC298_P0_2
J 0
(-1025 -1025);
DISPLAY 1.021277 (-1025 -1025);
PAINT AQUA (-1025 -1025);
DISPLAY INVISIBLE (-1025 -1025);
FORCEPROP 0 LAST $SEC 1
J 0
(-1025 -1025);
DISPLAY 0.680851 (-1025 -1025);
PAINT MONO (-1025 -1025);
DISPLAY INVISIBLE (-1025 -1025);
FORCEPROP 0 LAST CDS_SEC 1
J 0
(-1025 -1025);
DISPLAY 1.021277 (-1025 -1025);
DISPLAY INVISIBLE (-1025 -1025);
FORCEADD Q_CAP..1
(-675 -1225);
FORCEPROP 1 LAST PART_NUMBER CH6223MEA01
J 0
(-625 -1375);
DISPLAY 0.617021 (-625 -1375);
PAINT BLUE (-625 -1375);
DISPLAY INVISIBLE (-625 -1375);
FORCEPROP 1 LAST TOLERANCE 20%
J 0
(-625 -1225);
DISPLAY 0.617021 (-625 -1225);
PAINT SKYBLUE (-625 -1225);
FORCEPROP 1 LAST PACK_TYPE C0805
J 0
(-625 -1325);
DISPLAY 0.617021 (-625 -1325);
PAINT SKYBLUE (-625 -1325);
FORCEPROP 1 LAST VALUE 22UF
J 0
(-625 -1125);
DISPLAY 0.617021 (-625 -1125);
PAINT SKYBLUE (-625 -1125);
FORCEPROP 1 LAST MATERIAL X6S
J 0
(-625 -1275);
DISPLAY 0.617021 (-625 -1275);
PAINT SKYBLUE (-625 -1275);
FORCEPROP 1 LAST VOLTAGE 16V
J 0
(-625 -1175);
DISPLAY 0.617021 (-625 -1175);
PAINT SKYBLUE (-625 -1175);
FORCEPROP 1 LAST LOCATION PC302_P0_2
J 0
(-625 -1075);
DISPLAY 0.617021 (-625 -1075);
PAINT AQUA (-625 -1075);
FORCEPROP 1 LASTPIN (-675 -1125) $PN 1
J 0
(-665 -1145);
DISPLAY 0.617021 (-665 -1145);
PAINT MONO (-665 -1145);
FORCEPROP 1 LASTPIN (-675 -1325) $PN 2
J 0
(-665 -1345);
DISPLAY 0.617021 (-665 -1345);
PAINT MONO (-665 -1345);
FORCEPROP 2 LAST CDS_LIB pure_quanta
J 0
(-675 -1225);
DISPLAY INVISIBLE (-675 -1225);
FORCEPROP 1 LAST PATH I23
J 0
(-625 -1075);
DISPLAY 0.978723 (-625 -1075);
PAINT WHITE (-625 -1075);
DISPLAY INVISIBLE (-625 -1075);
FORCEPROP 1 LAST LOCATION PC302_P0_2
J 0
(-625 -1025);
DISPLAY 1.021277 (-625 -1025);
PAINT AQUA (-625 -1025);
DISPLAY INVISIBLE (-625 -1025);
FORCEPROP 0 LAST $SEC 1
J 0
(-625 -1025);
DISPLAY 0.680851 (-625 -1025);
PAINT MONO (-625 -1025);
DISPLAY INVISIBLE (-625 -1025);
FORCEPROP 0 LAST CDS_SEC 1
J 0
(-625 -1025);
DISPLAY 1.021277 (-625 -1025);
DISPLAY INVISIBLE (-625 -1025);
FORCEADD Q_CAP..1
(-275 -1225);
FORCEPROP 1 LAST PART_NUMBER CH6223MEA01
J 0
(-225 -1375);
DISPLAY 0.617021 (-225 -1375);
PAINT BLUE (-225 -1375);
DISPLAY INVISIBLE (-225 -1375);
FORCEPROP 1 LAST TOLERANCE 20%
J 0
(-225 -1225);
DISPLAY 0.617021 (-225 -1225);
PAINT SKYBLUE (-225 -1225);
FORCEPROP 1 LAST MATERIAL X6S
J 0
(-225 -1275);
DISPLAY 0.617021 (-225 -1275);
PAINT SKYBLUE (-225 -1275);
FORCEPROP 1 LAST VOLTAGE 16V
J 0
(-225 -1175);
DISPLAY 0.617021 (-225 -1175);
PAINT SKYBLUE (-225 -1175);
FORCEPROP 1 LAST VALUE 22UF
J 0
(-225 -1125);
DISPLAY 0.617021 (-225 -1125);
PAINT SKYBLUE (-225 -1125);
FORCEPROP 1 LAST PACK_TYPE C0805
J 0
(-225 -1325);
DISPLAY 0.617021 (-225 -1325);
PAINT SKYBLUE (-225 -1325);
FORCEPROP 1 LAST LOCATION PC304_P0_2
J 0
(-225 -1075);
DISPLAY 0.617021 (-225 -1075);
PAINT AQUA (-225 -1075);
FORCEPROP 1 LASTPIN (-275 -1125) $PN 1
J 0
(-265 -1145);
DISPLAY 0.617021 (-265 -1145);
PAINT MONO (-265 -1145);
FORCEPROP 1 LASTPIN (-275 -1325) $PN 2
J 0
(-265 -1345);
DISPLAY 0.617021 (-265 -1345);
PAINT MONO (-265 -1345);
FORCEPROP 2 LAST CDS_LIB pure_quanta
J 0
(-275 -1225);
DISPLAY INVISIBLE (-275 -1225);
FORCEPROP 1 LAST PATH I24
J 0
(-225 -1075);
DISPLAY 0.978723 (-225 -1075);
PAINT WHITE (-225 -1075);
DISPLAY INVISIBLE (-225 -1075);
FORCEPROP 1 LAST LOCATION PC304_P0_2
J 0
(-225 -1025);
DISPLAY 1.021277 (-225 -1025);
PAINT AQUA (-225 -1025);
DISPLAY INVISIBLE (-225 -1025);
FORCEPROP 0 LAST $SEC 1
J 0
(-225 -1025);
DISPLAY 0.680851 (-225 -1025);
PAINT MONO (-225 -1025);
DISPLAY INVISIBLE (-225 -1025);
FORCEPROP 0 LAST CDS_SEC 1
J 0
(-225 -1025);
DISPLAY 1.021277 (-225 -1025);
DISPLAY INVISIBLE (-225 -1025);
FORCEADD UNIVERSAL_GND..1
(-4275 400);
FORCEPROP 3 LASTPIN (-4275 450) SIG_NAME GND\g
J 0
(-4265 460);
DISPLAY 0.659574 (-4265 460);
PAINT MONO (-4265 460);
DISPLAY INVISIBLE (-4265 460);
FORCEPROP 1 LAST HDL_POWER GND
J 1
(-4250 325);
DISPLAY 0.872340 (-4250 325);
PAINT GREEN (-4250 325);
DISPLAY INVISIBLE (-4250 325);
FORCEPROP 2 LAST CDS_LIB logical_power
J 0
(-4275 400);
PAINT MONO (-4275 400);
DISPLAY INVISIBLE (-4275 400);
FORCEPROP 1 LAST PATH I25
J 0
(-4200 400);
DISPLAY 0.872340 (-4200 400);
PAINT AQUA (-4200 400);
DISPLAY INVISIBLE (-4200 400);
FORCEADD Q_RES..2
(-4325 2375);
FORCEPROP 1 LAST PART_NUMBER CS00002JB13
J 0
(-4285 2250);
DISPLAY 0.617021 (-4285 2250);
PAINT BLUE (-4285 2250);
DISPLAY INVISIBLE (-4285 2250);
FORCEPROP 1 LAST PACK_TYPE 0402LF
J 0
(-4285 2200);
DISPLAY 0.617021 (-4285 2200);
PAINT SKYBLUE (-4285 2200);
FORCEPROP 1 LAST VALUE 0
J 0
(-4280 2450);
DISPLAY 0.617021 (-4280 2450);
PAINT SKYBLUE (-4280 2450);
FORCEPROP 1 LAST TOLERANCE 5%
J 0
(-4280 2400);
DISPLAY 0.617021 (-4280 2400);
PAINT SKYBLUE (-4280 2400);
FORCEPROP 1 LAST WATTAGE 1/16W
J 0
(-4285 2350);
DISPLAY 0.617021 (-4285 2350);
PAINT SKYBLUE (-4285 2350);
FORCEPROP 1 LAST MATERIAL CHIP
J 0
(-4285 2300);
DISPLAY 0.617021 (-4285 2300);
PAINT SKYBLUE (-4285 2300);
FORCEPROP 1 LAST LOCATION PR402
J 0
(-4280 2500);
DISPLAY 0.617021 (-4280 2500);
PAINT AQUA (-4280 2500);
FORCEPROP 2 LAST CDS_LIB pure_quanta
J 0
(-4325 2375);
DISPLAY INVISIBLE (-4325 2375);
FORCEPROP 1 LAST PATH I26
J 0
(-4275 2550);
DISPLAY 0.978723 (-4275 2550);
PAINT WHITE (-4275 2550);
DISPLAY INVISIBLE (-4275 2550);
FORCEPROP 0 LAST $SEC 1
J 0
(-4275 2550);
DISPLAY INVISIBLE (-4275 2550);
FORCEPROP 0 LAST CDS_SEC 1
J 0
(-4275 2550);
DISPLAY INVISIBLE (-4275 2550);
FORCEPROP 1 LASTPIN (-4325 2475) $PN 1
J 0
(-4320 2437);
DISPLAY 0.787234 (-4320 2437);
PAINT MONO (-4320 2437);
DISPLAY INVISIBLE (-4320 2437);
FORCEPROP 1 LASTPIN (-4325 2275) $PN 2
J 0
(-4320 2285);
DISPLAY 0.787234 (-4320 2285);
PAINT MONO (-4320 2285);
DISPLAY INVISIBLE (-4320 2285);
FORCEADD VCC15..1
(-4325 2600);
FORCEPROP 3 LASTPIN (-4325 2550) SIG_NAME P5V\g
J 0
(-4315 2560);
DISPLAY 0.659574 (-4315 2560);
PAINT MONO (-4315 2560);
DISPLAY INVISIBLE (-4315 2560);
FORCEPROP 1 LAST HDL_POWER P5V
J 1
(-4325 2650);
DISPLAY 0.617021 (-4325 2650);
PAINT GREEN (-4325 2650);
FORCEPROP 2 LAST CDS_LIB logical_power
J 0
(-4325 2600);
DISPLAY INVISIBLE (-4325 2600);
FORCEPROP 1 LAST PATH I27
J 0
(-4275 2625);
DISPLAY 0.872340 (-4275 2625);
PAINT AQUA (-4275 2625);
DISPLAY INVISIBLE (-4275 2625);
FORCEADD UNIVERSAL_GND..1
(-4175 -25);
FORCEPROP 3 LASTPIN (-4175 25) SIG_NAME GND\g
J 0
(-4165 35);
DISPLAY 0.659574 (-4165 35);
PAINT MONO (-4165 35);
DISPLAY INVISIBLE (-4165 35);
FORCEPROP 1 LAST HDL_POWER GND
J 1
(-4150 -100);
DISPLAY 0.872340 (-4150 -100);
PAINT GREEN (-4150 -100);
DISPLAY INVISIBLE (-4150 -100);
FORCEPROP 2 LAST CDS_LIB logical_power
J 0
(-4175 -25);
PAINT MONO (-4175 -25);
DISPLAY INVISIBLE (-4175 -25);
FORCEPROP 1 LAST PATH I28
J 0
(-4100 -25);
DISPLAY 0.872340 (-4100 -25);
PAINT AQUA (-4100 -25);
DISPLAY INVISIBLE (-4100 -25);
FORCEADD Q_RES..2
R 2
(-4175 200);
FORCEPROP 1 LAST PART_NUMBER CS28872FB01
J 2
(-4215 75);
DISPLAY 0.617021 (-4215 75);
PAINT BLUE (-4215 75);
DISPLAY INVISIBLE (-4215 75);
FORCEPROP 1 LAST PACK_TYPE 0402LF
J 2
(-4215 25);
DISPLAY 0.617021 (-4215 25);
PAINT SKYBLUE (-4215 25);
FORCEPROP 1 LAST VALUE 8.87K
J 2
(-4220 275);
DISPLAY 0.617021 (-4220 275);
PAINT SKYBLUE (-4220 275);
FORCEPROP 1 LAST TOLERANCE 1%
J 2
(-4220 225);
DISPLAY 0.617021 (-4220 225);
PAINT SKYBLUE (-4220 225);
FORCEPROP 1 LAST MATERIAL EMPTY
J 2
(-4215 125);
DISPLAY 0.617021 (-4215 125);
PAINT RED (-4215 125);
FORCEPROP 1 LAST WATTAGE 1/16W
J 2
(-4215 175);
DISPLAY 0.617021 (-4215 175);
PAINT SKYBLUE (-4215 175);
FORCEPROP 1 LAST LOCATION PR151
J 2
(-4220 325);
DISPLAY 0.617021 (-4220 325);
PAINT AQUA (-4220 325);
FORCEPROP 1 LASTPIN (-4175 300) $PN 1
J 2
(-4180 262);
DISPLAY 0.617021 (-4180 262);
PAINT MONO (-4180 262);
FORCEPROP 1 LASTPIN (-4175 100) $PN 2
J 2
(-4180 110);
DISPLAY 0.617021 (-4180 110);
PAINT MONO (-4180 110);
FORCEPROP 2 LAST CDS_LIB pure_quanta
J 2
(-4175 200);
DISPLAY INVISIBLE (-4175 200);
FORCEPROP 1 LAST PATH I29
J 2
(-4225 375);
DISPLAY 0.978723 (-4225 375);
PAINT WHITE (-4225 375);
DISPLAY INVISIBLE (-4225 375);
FORCEPROP 0 LAST $SEC 1
J 0
(-4200 375);
DISPLAY 0.680851 (-4200 375);
PAINT MONO (-4200 375);
DISPLAY INVISIBLE (-4200 375);
FORCEPROP 0 LAST CDS_SEC 1
J 0
(-4200 375);
DISPLAY 1.021277 (-4200 375);
DISPLAY INVISIBLE (-4200 375);
FORCEADD UNIVERSAL_GND..1
(-4300 -2400);
FORCEPROP 3 LASTPIN (-4300 -2350) SIG_NAME GND\g
J 0
(-4290 -2340);
DISPLAY 0.659574 (-4290 -2340);
PAINT MONO (-4290 -2340);
DISPLAY INVISIBLE (-4290 -2340);
FORCEPROP 1 LAST HDL_POWER GND
J 1
(-4275 -2475);
DISPLAY 0.872340 (-4275 -2475);
PAINT GREEN (-4275 -2475);
DISPLAY INVISIBLE (-4275 -2475);
FORCEPROP 2 LAST CDS_LIB logical_power
J 0
(-4300 -2400);
PAINT MONO (-4300 -2400);
DISPLAY INVISIBLE (-4300 -2400);
FORCEPROP 1 LAST PATH I3
J 0
(-4225 -2400);
DISPLAY 0.872340 (-4225 -2400);
PAINT AQUA (-4225 -2400);
DISPLAY INVISIBLE (-4225 -2400);
FORCEADD OFFPAGE..1
(-3600 100);
FORCEPROP 2 LAST $XR0 266 
J 0
(-3852 100);
DISPLAY 0.638298 (-3852 100);
PAINT MONO (-3852 100);
FORCEPROP 1 LAST COMMENT_BODY TRUE
J 0
(-3475 0);
DISPLAY 0.872340 (-3475 0);
PAINT GREEN (-3475 0);
DISPLAY INVISIBLE (-3475 0);
FORCEPROP 1 LAST OFFPAGE TRUE
J 0
(-3275 -25);
DISPLAY 0.872340 (-3275 -25);
PAINT GREEN (-3275 -25);
DISPLAY INVISIBLE (-3275 -25);
FORCEPROP 2 LAST CDS_LIB standard
J 0
(-3600 100);
DISPLAY INVISIBLE (-3600 100);
FORCEPROP 2 LAST PATH I30
J 0
(-3850 150);
DISPLAY 1.021277 (-3850 150);
DISPLAY INVISIBLE (-3850 150);
FORCEADD OFFPAGE..5
(-3600 200);
FORCEPROP 2 LAST $XR4 266 
J 0
(-3885 236);
DISPLAY 0.638298 (-3885 236);
PAINT MONO (-3885 236);
FORCEPROP 2 LAST $XR3 270 
J 0
(-4005 164);
DISPLAY 0.638298 (-4005 164);
PAINT MONO (-4005 164);
FORCEPROP 2 LAST $XR2 269 
J 0
(-3885 164);
DISPLAY 0.638298 (-3885 164);
PAINT MONO (-3885 164);
FORCEPROP 2 LAST $XR1 268 
J 0
(-4005 200);
DISPLAY 0.638298 (-4005 200);
PAINT MONO (-4005 200);
FORCEPROP 2 LAST $XR0 267 
J 0
(-3885 200);
DISPLAY 0.638298 (-3885 200);
PAINT MONO (-3885 200);
FORCEPROP 1 LAST COMMENT_BODY TRUE
J 0
(-3500 125);
DISPLAY 0.872340 (-3500 125);
PAINT GREEN (-3500 125);
DISPLAY INVISIBLE (-3500 125);
FORCEPROP 1 LAST OFFPAGE TRUE
J 0
(-3275 75);
DISPLAY 0.872340 (-3275 75);
PAINT GREEN (-3275 75);
DISPLAY INVISIBLE (-3275 75);
FORCEPROP 2 LAST CDS_LIB standard
J 0
(-3600 200);
DISPLAY INVISIBLE (-3600 200);
FORCEPROP 2 LAST PATH I31
J 0
(-3875 275);
DISPLAY 1.021277 (-3875 275);
DISPLAY INVISIBLE (-3875 275);
FORCEADD OFFPAGE..1
(-3600 600);
FORCEPROP 2 LAST $XR6 272 
J 0
(-4572 600);
DISPLAY 0.638298 (-4572 600);
PAINT MONO (-4572 600);
FORCEPROP 2 LAST $XR5 271 
J 0
(-4452 600);
DISPLAY 0.638298 (-4452 600);
PAINT MONO (-4452 600);
FORCEPROP 2 LAST $XR4 270 
J 0
(-4332 600);
DISPLAY 0.638298 (-4332 600);
PAINT MONO (-4332 600);
FORCEPROP 2 LAST $XR3 269 
J 0
(-4212 600);
DISPLAY 0.638298 (-4212 600);
PAINT MONO (-4212 600);
FORCEPROP 2 LAST $XR2 268 
J 0
(-4092 600);
DISPLAY 0.638298 (-4092 600);
PAINT MONO (-4092 600);
FORCEPROP 2 LAST $XR1 267 
J 0
(-3972 600);
DISPLAY 0.638298 (-3972 600);
PAINT MONO (-3972 600);
FORCEPROP 2 LAST $XR0 266 
J 0
(-3852 600);
DISPLAY 0.638298 (-3852 600);
PAINT MONO (-3852 600);
FORCEPROP 1 LAST COMMENT_BODY TRUE
J 0
(-3475 500);
DISPLAY 0.872340 (-3475 500);
PAINT GREEN (-3475 500);
DISPLAY INVISIBLE (-3475 500);
FORCEPROP 1 LAST OFFPAGE TRUE
J 0
(-3275 475);
DISPLAY 0.872340 (-3275 475);
PAINT GREEN (-3275 475);
DISPLAY INVISIBLE (-3275 475);
FORCEPROP 2 LAST CDS_LIB standard
J 0
(-3600 600);
DISPLAY INVISIBLE (-3600 600);
FORCEPROP 2 LAST PATH I32
J 0
(-3850 650);
DISPLAY 1.021277 (-3850 650);
DISPLAY INVISIBLE (-3850 650);
FORCEADD OFFPAGE..5
(-3600 700);
FORCEPROP 2 LAST $XR0 266 
J 0
(-3885 700);
DISPLAY 0.638298 (-3885 700);
PAINT MONO (-3885 700);
FORCEPROP 1 LAST COMMENT_BODY TRUE
J 0
(-3500 625);
DISPLAY 0.872340 (-3500 625);
PAINT GREEN (-3500 625);
DISPLAY INVISIBLE (-3500 625);
FORCEPROP 1 LAST OFFPAGE TRUE
J 0
(-3275 575);
DISPLAY 0.872340 (-3275 575);
PAINT GREEN (-3275 575);
DISPLAY INVISIBLE (-3275 575);
FORCEPROP 2 LAST CDS_LIB standard
J 0
(-3600 700);
DISPLAY INVISIBLE (-3600 700);
FORCEPROP 2 LAST PATH I33
J 0
(-3875 750);
DISPLAY 1.021277 (-3875 750);
DISPLAY INVISIBLE (-3875 750);
FORCEADD Q_CAP..2
(-3450 500);
FORCEPROP 1 LAST PART_NUMBER CH4104K1B00
J 1
(-3175 550);
DISPLAY 0.617021 (-3175 550);
PAINT BLUE (-3175 550);
DISPLAY INVISIBLE (-3175 550);
FORCEPROP 1 LAST PACK_TYPE 0402
J 1
(-2950 500);
DISPLAY 0.617021 (-2950 500);
PAINT SKYBLUE (-2950 500);
FORCEPROP 1 LAST MATERIAL X7R
J 0
(-3000 550);
DISPLAY 0.617021 (-3000 550);
PAINT SKYBLUE (-3000 550);
FORCEPROP 1 LAST TOLERANCE 10%
J 2
(-2800 550);
DISPLAY 0.617021 (-2800 550);
PAINT SKYBLUE (-2800 550);
FORCEPROP 1 LAST VOLTAGE 25V
J 0
(-3125 500);
DISPLAY 0.617021 (-3125 500);
PAINT SKYBLUE (-3125 500);
FORCEPROP 1 LAST VALUE 0.1UF
J 2
(-3150 500);
DISPLAY 0.617021 (-3150 500);
PAINT SKYBLUE (-3150 500);
FORCEPROP 1 LAST LOCATION PC1356
J 1
(-3650 500);
DISPLAY 0.617021 (-3650 500);
PAINT AQUA (-3650 500);
FORCEPROP 1 LASTPIN (-3550 500) $PN 1
J 0
(-3560 515);
DISPLAY 0.617021 (-3560 515);
FORCEPROP 1 LASTPIN (-3350 500) $PN 2
J 0
(-3365 515);
DISPLAY 0.617021 (-3365 515);
FORCEPROP 2 LAST CDS_LIB pure_quanta
J 0
(-3450 500);
PAINT MONO (-3450 500);
DISPLAY INVISIBLE (-3450 500);
FORCEPROP 1 LAST PATH I34
J 0
(-3450 700);
DISPLAY 0.978723 (-3450 700);
PAINT WHITE (-3450 700);
DISPLAY INVISIBLE (-3450 700);
FORCEPROP 2 LAST $SEC 1
J 0
(-3450 750);
DISPLAY 0.680851 (-3450 750);
PAINT MONO (-3450 750);
DISPLAY INVISIBLE (-3450 750);
FORCEPROP 2 LAST CDS_SEC 1
J 0
(-3450 750);
DISPLAY 1.021277 (-3450 750);
DISPLAY INVISIBLE (-3450 750);
FORCEADD UNIVERSAL_GND..1
(-3775 950);
FORCEPROP 3 LASTPIN (-3775 1000) SIG_NAME GND\g
J 0
(-3765 1010);
DISPLAY 0.659574 (-3765 1010);
PAINT MONO (-3765 1010);
DISPLAY INVISIBLE (-3765 1010);
FORCEPROP 1 LAST HDL_POWER GND
J 1
(-3750 875);
DISPLAY 0.872340 (-3750 875);
PAINT GREEN (-3750 875);
DISPLAY INVISIBLE (-3750 875);
FORCEPROP 2 LAST CDS_LIB logical_power
J 0
(-3775 950);
PAINT MONO (-3775 950);
DISPLAY INVISIBLE (-3775 950);
FORCEPROP 1 LAST PATH I35
J 0
(-3700 950);
DISPLAY 0.872340 (-3700 950);
PAINT AQUA (-3700 950);
DISPLAY INVISIBLE (-3700 950);
FORCEADD Q_CAP..1
(-3775 1200);
FORCEPROP 1 LAST PART_NUMBER CH5222KEB01
J 0
(-3725 1025);
DISPLAY 0.617021 (-3725 1025);
PAINT BLUE (-3725 1025);
DISPLAY INVISIBLE (-3725 1025);
FORCEPROP 1 LAST PACK_TYPE C0402
J 0
(-3725 1075);
DISPLAY 0.617021 (-3725 1075);
PAINT SKYBLUE (-3725 1075);
FORCEPROP 1 LAST VOLTAGE 10V
J 0
(-3725 1225);
DISPLAY 0.617021 (-3725 1225);
PAINT SKYBLUE (-3725 1225);
FORCEPROP 1 LAST VALUE 2.2UF
J 0
(-3725 1275);
DISPLAY 0.617021 (-3725 1275);
PAINT SKYBLUE (-3725 1275);
FORCEPROP 1 LAST TOLERANCE 10%
J 0
(-3725 1175);
DISPLAY 0.617021 (-3725 1175);
PAINT SKYBLUE (-3725 1175);
FORCEPROP 1 LAST MATERIAL X6S
J 0
(-3725 1125);
DISPLAY 0.617021 (-3725 1125);
PAINT SKYBLUE (-3725 1125);
FORCEPROP 1 LAST LOCATION PC293
J 0
(-3725 1325);
DISPLAY 0.617021 (-3725 1325);
PAINT AQUA (-3725 1325);
FORCEPROP 1 LASTPIN (-3775 1300) $PN 1
J 0
(-3765 1280);
DISPLAY 0.617021 (-3765 1280);
PAINT MONO (-3765 1280);
FORCEPROP 1 LASTPIN (-3775 1100) $PN 2
J 0
(-3765 1080);
DISPLAY 0.617021 (-3765 1080);
PAINT MONO (-3765 1080);
FORCEPROP 2 LAST CDS_LIB pure_quanta
J 0
(-3775 1200);
DISPLAY INVISIBLE (-3775 1200);
FORCEPROP 1 LAST PATH I36
J 0
(-3725 1350);
DISPLAY 0.978723 (-3725 1350);
PAINT WHITE (-3725 1350);
DISPLAY INVISIBLE (-3725 1350);
FORCEPROP 1 LAST LOCATION PC293
J 0
(-3725 1375);
DISPLAY 1.021277 (-3725 1375);
PAINT AQUA (-3725 1375);
DISPLAY INVISIBLE (-3725 1375);
FORCEPROP 0 LAST $SEC 1
J 0
(-3725 1375);
DISPLAY 0.680851 (-3725 1375);
PAINT MONO (-3725 1375);
DISPLAY INVISIBLE (-3725 1375);
FORCEPROP 0 LAST CDS_SEC 1
J 0
(-3725 1375);
DISPLAY 1.021277 (-3725 1375);
DISPLAY INVISIBLE (-3725 1375);
FORCEADD Q_RES..2
(-3775 1700);
FORCEPROP 1 LAST PART_NUMBER CS-2202FB01
J 0
(-3735 1575);
DISPLAY 0.617021 (-3735 1575);
PAINT BLUE (-3735 1575);
DISPLAY INVISIBLE (-3735 1575);
FORCEPROP 1 LAST VALUE 2.2
J 0
(-3730 1775);
DISPLAY 0.617021 (-3730 1775);
PAINT SKYBLUE (-3730 1775);
FORCEPROP 1 LAST PACK_TYPE 0402LF
J 0
(-3735 1525);
DISPLAY 0.617021 (-3735 1525);
PAINT SKYBLUE (-3735 1525);
FORCEPROP 1 LAST TOLERANCE 1%
J 0
(-3730 1725);
DISPLAY 0.617021 (-3730 1725);
PAINT SKYBLUE (-3730 1725);
FORCEPROP 1 LAST MATERIAL CHIP
J 0
(-3735 1625);
DISPLAY 0.617021 (-3735 1625);
PAINT SKYBLUE (-3735 1625);
FORCEPROP 1 LAST WATTAGE 1/16W
J 0
(-3735 1675);
DISPLAY 0.617021 (-3735 1675);
PAINT SKYBLUE (-3735 1675);
FORCEPROP 1 LAST LOCATION PR153
J 0
(-3730 1825);
DISPLAY 0.617021 (-3730 1825);
PAINT AQUA (-3730 1825);
FORCEPROP 1 LASTPIN (-3775 1800) $PN 1
J 0
(-3770 1762);
DISPLAY 0.617021 (-3770 1762);
PAINT MONO (-3770 1762);
FORCEPROP 1 LASTPIN (-3775 1600) $PN 2
J 0
(-3770 1610);
DISPLAY 0.617021 (-3770 1610);
PAINT MONO (-3770 1610);
FORCEPROP 2 LAST CDS_LIB pure_quanta
J 0
(-3775 1700);
DISPLAY INVISIBLE (-3775 1700);
FORCEPROP 1 LAST PATH I37
J 0
(-3725 1875);
DISPLAY 0.978723 (-3725 1875);
PAINT WHITE (-3725 1875);
DISPLAY INVISIBLE (-3725 1875);
FORCEPROP 1 LAST LOCATION PR153
J 0
(-3725 1875);
DISPLAY 1.021277 (-3725 1875);
PAINT AQUA (-3725 1875);
DISPLAY INVISIBLE (-3725 1875);
FORCEPROP 0 LAST $SEC 1
J 0
(-3725 1875);
DISPLAY 0.680851 (-3725 1875);
PAINT MONO (-3725 1875);
DISPLAY INVISIBLE (-3725 1875);
FORCEPROP 0 LAST CDS_SEC 1
J 0
(-3725 1875);
DISPLAY 1.021277 (-3725 1875);
DISPLAY INVISIBLE (-3725 1875);
FORCEADD UNIVERSAL_GND..1
(-3350 1475);
FORCEPROP 3 LASTPIN (-3350 1525) SIG_NAME GND\g
J 0
(-3340 1535);
DISPLAY 0.659574 (-3340 1535);
PAINT MONO (-3340 1535);
DISPLAY INVISIBLE (-3340 1535);
FORCEPROP 1 LAST HDL_POWER GND
J 1
(-3325 1400);
DISPLAY 0.872340 (-3325 1400);
PAINT GREEN (-3325 1400);
DISPLAY INVISIBLE (-3325 1400);
FORCEPROP 2 LAST CDS_LIB logical_power
J 0
(-3350 1475);
PAINT MONO (-3350 1475);
DISPLAY INVISIBLE (-3350 1475);
FORCEPROP 1 LAST PATH I38
J 0
(-3275 1475);
DISPLAY 0.872340 (-3275 1475);
PAINT AQUA (-3275 1475);
DISPLAY INVISIBLE (-3275 1475);
FORCEADD Q_CAP..1
(-3350 1700);
FORCEPROP 1 LAST PART_NUMBER CH5222KEB01
J 0
(-3300 1575);
DISPLAY 0.617021 (-3300 1575);
PAINT BLUE (-3300 1575);
DISPLAY INVISIBLE (-3300 1575);
FORCEPROP 1 LAST PACK_TYPE C0402
J 0
(-3300 1525);
DISPLAY 0.617021 (-3300 1525);
PAINT SKYBLUE (-3300 1525);
FORCEPROP 1 LAST VOLTAGE 10V
J 0
(-3300 1725);
DISPLAY 0.617021 (-3300 1725);
PAINT SKYBLUE (-3300 1725);
FORCEPROP 1 LAST VALUE 2.2UF
J 0
(-3300 1775);
DISPLAY 0.617021 (-3300 1775);
PAINT SKYBLUE (-3300 1775);
FORCEPROP 1 LAST TOLERANCE 10%
J 0
(-3300 1675);
DISPLAY 0.617021 (-3300 1675);
PAINT SKYBLUE (-3300 1675);
FORCEPROP 1 LAST MATERIAL X6S
J 0
(-3300 1625);
DISPLAY 0.617021 (-3300 1625);
PAINT SKYBLUE (-3300 1625);
FORCEPROP 1 LAST LOCATION PC295_P0_1
J 0
(-3300 1825);
DISPLAY 0.617021 (-3300 1825);
PAINT AQUA (-3300 1825);
FORCEPROP 1 LASTPIN (-3350 1800) $PN 1
J 0
(-3340 1780);
DISPLAY 0.617021 (-3340 1780);
PAINT MONO (-3340 1780);
FORCEPROP 1 LASTPIN (-3350 1600) $PN 2
J 0
(-3340 1580);
DISPLAY 0.617021 (-3340 1580);
PAINT MONO (-3340 1580);
FORCEPROP 2 LAST CDS_LIB pure_quanta
J 0
(-3350 1700);
DISPLAY INVISIBLE (-3350 1700);
FORCEPROP 1 LAST PATH I39
J 0
(-3300 1850);
DISPLAY 0.978723 (-3300 1850);
PAINT WHITE (-3300 1850);
DISPLAY INVISIBLE (-3300 1850);
FORCEPROP 1 LAST LOCATION PC295_P0_1
J 0
(-3300 1875);
DISPLAY 1.021277 (-3300 1875);
PAINT AQUA (-3300 1875);
DISPLAY INVISIBLE (-3300 1875);
FORCEPROP 0 LAST $SEC 1
J 0
(-3300 1875);
DISPLAY 0.680851 (-3300 1875);
PAINT MONO (-3300 1875);
DISPLAY INVISIBLE (-3300 1875);
FORCEPROP 0 LAST CDS_SEC 1
J 0
(-3300 1875);
DISPLAY 1.021277 (-3300 1875);
DISPLAY INVISIBLE (-3300 1875);
FORCEADD OFFPAGE..1
(-3650 -2725);
FORCEPROP 2 LAST $XR0 266 
J 0
(-3902 -2725);
DISPLAY 0.638298 (-3902 -2725);
PAINT MONO (-3902 -2725);
FORCEPROP 1 LAST COMMENT_BODY TRUE
J 0
(-3525 -2825);
DISPLAY 0.872340 (-3525 -2825);
PAINT GREEN (-3525 -2825);
DISPLAY INVISIBLE (-3525 -2825);
FORCEPROP 1 LAST OFFPAGE TRUE
J 0
(-3325 -2850);
DISPLAY 0.872340 (-3325 -2850);
PAINT GREEN (-3325 -2850);
DISPLAY INVISIBLE (-3325 -2850);
FORCEPROP 2 LAST CDS_LIB standard
J 0
(-3650 -2725);
DISPLAY INVISIBLE (-3650 -2725);
FORCEPROP 2 LAST PATH I4
J 0
(-3900 -2675);
DISPLAY 1.021277 (-3900 -2675);
DISPLAY INVISIBLE (-3900 -2675);
FORCEADD ISL99390FRZTR5935..1
(-2250 700);
FORCEPROP 1 LAST PART_NUMBER AL099390004
J 0
(-2550 1500);
DISPLAY 0.617021 (-2550 1500);
PAINT BLUE (-2550 1500);
DISPLAY INVISIBLE (-2550 1500);
FORCEPROP 2 LAST VALUE ISL99390FRZ-TR5935
J 0
(-2550 1650);
DISPLAY 0.617021 (-2550 1650);
PAINT SKYBLUE (-2550 1650);
FORCEPROP 1 LAST MATERIAL IC
J 0
(-2550 1425);
DISPLAY 0.617021 (-2550 1425);
PAINT SKYBLUE (-2550 1425);
FORCEPROP 2 LAST PART_TYPE SMLF
J 0
(-2550 1700);
DISPLAY 0.808511 (-2550 1700);
FORCEPROP 1 LAST LOCATION PU13_P0_1
J 0
(-2550 1575);
DISPLAY 0.617021 (-2550 1575);
PAINT AQUA (-2550 1575);
FORCEPROP 2 LASTPIN (-1850 250) $PN 2
J 0
(-1840 260);
DISPLAY 0.617021 (-1840 260);
PAINT MONO (-1840 260);
FORCEPROP 2 LASTPIN (-1850 1050) $PN 33
J 0
(-1840 1060);
DISPLAY 0.617021 (-1840 1060);
PAINT MONO (-1840 1060);
FORCEPROP 2 LASTPIN (-2700 450) $PN 31
J 2
(-2710 460);
DISPLAY 0.617021 (-2710 460);
PAINT MONO (-2710 460);
FORCEPROP 2 LASTPIN (-2700 850) $PN 35
J 2
(-2710 860);
DISPLAY 0.617021 (-2710 860);
PAINT MONO (-2710 860);
FORCEPROP 2 LASTPIN (-1850 400) $PN 6
J 0
(-1840 410);
DISPLAY 0.617021 (-1840 410);
PAINT MONO (-1840 410);
FORCEPROP 2 LASTPIN (-1850 350) $PN 41
J 0
(-1840 360);
DISPLAY 0.617021 (-1840 360);
PAINT MONO (-1840 360);
FORCEPROP 2 LASTPIN (-2700 700) $PN 38
J 2
(-2710 710);
DISPLAY 0.617021 (-2710 710);
PAINT MONO (-2710 710);
FORCEPROP 2 LASTPIN (-2700 400) $PN 37
J 2
(-2710 410);
DISPLAY 0.617021 (-2710 410);
PAINT MONO (-2710 410);
FORCEPROP 2 LASTPIN (-1850 200) $PN 5
J 0
(-1840 210);
DISPLAY 0.617021 (-1840 210);
PAINT MONO (-1840 210);
FORCEPROP 2 LASTPIN (-1850 150) $PN 7_9-20_24
J 0
(-1840 160);
DISPLAY 0.617021 (-1840 160);
PAINT MONO (-1840 160);
FORCEPROP 2 LASTPIN (-1850 100) $PN 40
J 0
(-1840 110);
DISPLAY 0.617021 (-1840 110);
PAINT MONO (-1840 110);
FORCEPROP 2 LASTPIN (-1850 800) $PN 32
J 0
(-1840 810);
DISPLAY 0.617021 (-1840 810);
PAINT MONO (-1840 810);
FORCEPROP 2 LASTPIN (-2700 1350) $PN 4
J 2
(-2710 1360);
DISPLAY 0.617021 (-2710 1360);
PAINT MONO (-2710 1360);
FORCEPROP 2 LASTPIN (-2700 100) $PN 34
J 2
(-2710 110);
DISPLAY 0.617021 (-2710 110);
PAINT MONO (-2710 110);
FORCEPROP 2 LASTPIN (-2700 600) $PN 39
J 2
(-2710 610);
DISPLAY 0.617021 (-2710 610);
PAINT MONO (-2710 610);
FORCEPROP 2 LASTPIN (-1850 700) $PN 10_19
J 0
(-1840 710);
DISPLAY 0.617021 (-1840 710);
PAINT MONO (-1840 710);
FORCEPROP 2 LASTPIN (-2700 200) $PN 36
J 2
(-2710 210);
DISPLAY 0.617021 (-2710 210);
PAINT MONO (-2710 210);
FORCEPROP 2 LASTPIN (-2700 1050) $PN 3
J 2
(-2710 1060);
DISPLAY 0.617021 (-2710 1060);
PAINT MONO (-2710 1060);
FORCEPROP 2 LASTPIN (-1850 1350) $PN 25_29
J 0
(-1840 1360);
DISPLAY 0.617021 (-1840 1360);
PAINT MONO (-1840 1360);
FORCEPROP 2 LASTPIN (-1850 1300) $PN 30
J 0
(-1840 1310);
DISPLAY 0.617021 (-1840 1310);
PAINT MONO (-1840 1310);
FORCEPROP 2 LASTPIN (-1850 450) $PN 1
J 0
(-1840 460);
DISPLAY 0.617021 (-1840 460);
PAINT MONO (-1840 460);
FORCEPROP 1 LAST NEEDS_NO_SIZE TRUE
J 0
(-2250 700);
DISPLAY 0.723404 (-2250 700);
PAINT GREEN (-2250 700);
DISPLAY INVISIBLE (-2250 700);
FORCEPROP 1 LAST CDS_LMAN_SYM_OUTLINE -300,700,250,-650
J 0
(-2250 700);
DISPLAY 0.468085 (-2250 700);
PAINT GREEN (-2250 700);
DISPLAY INVISIBLE (-2250 700);
FORCEPROP 2 LAST CDS_LIB pure_quanta
J 0
(-2250 700);
DISPLAY INVISIBLE (-2250 700);
FORCEPROP 1 LAST PATH I40
J 0
(-2250 700);
DISPLAY 0.723404 (-2250 700);
PAINT GREEN (-2250 700);
DISPLAY INVISIBLE (-2250 700);
FORCEPROP 2 LAST $SEC 1
J 0
(-2550 1750);
DISPLAY 0.680851 (-2550 1750);
PAINT MONO (-2550 1750);
DISPLAY INVISIBLE (-2550 1750);
FORCEPROP 2 LAST CDS_SEC 1
J 0
(-2550 1750);
DISPLAY 1.021277 (-2550 1750);
DISPLAY INVISIBLE (-2550 1750);
FORCEADD VCC15..1
(-3675 2600);
FORCEPROP 3 LASTPIN (-3675 2550) SIG_NAME P3V3\g
J 0
(-3665 2560);
DISPLAY 0.659574 (-3665 2560);
PAINT MONO (-3665 2560);
DISPLAY INVISIBLE (-3665 2560);
FORCEPROP 1 LAST HDL_POWER P3V3
J 1
(-3675 2650);
DISPLAY 0.617021 (-3675 2650);
PAINT GREEN (-3675 2650);
FORCEPROP 2 LAST CDS_LIB logical_power
J 0
(-3675 2600);
DISPLAY INVISIBLE (-3675 2600);
FORCEPROP 1 LAST PATH I41
J 0
(-3625 2625);
DISPLAY 0.872340 (-3625 2625);
PAINT AQUA (-3625 2625);
DISPLAY INVISIBLE (-3625 2625);
FORCEADD Q_RES..2
(-3675 2375);
FORCEPROP 1 LAST PART_NUMBER CS00002JB13
J 0
(-3635 2250);
DISPLAY 0.617021 (-3635 2250);
PAINT BLUE (-3635 2250);
DISPLAY INVISIBLE (-3635 2250);
FORCEPROP 1 LAST VALUE 0
J 0
(-3630 2450);
DISPLAY 0.617021 (-3630 2450);
PAINT SKYBLUE (-3630 2450);
FORCEPROP 1 LAST TOLERANCE 5%
J 0
(-3630 2400);
DISPLAY 0.617021 (-3630 2400);
PAINT SKYBLUE (-3630 2400);
FORCEPROP 1 LAST MATERIAL EMPTY
J 0
(-3635 2300);
DISPLAY 0.617021 (-3635 2300);
PAINT RED (-3635 2300);
FORCEPROP 1 LAST WATTAGE 1/16W
J 0
(-3635 2350);
DISPLAY 0.617021 (-3635 2350);
PAINT SKYBLUE (-3635 2350);
FORCEPROP 1 LAST PACK_TYPE 0402LF
J 0
(-3635 2200);
DISPLAY 0.617021 (-3635 2200);
PAINT SKYBLUE (-3635 2200);
FORCEPROP 1 LAST LOCATION PR403
J 0
(-3630 2500);
DISPLAY 0.617021 (-3630 2500);
PAINT AQUA (-3630 2500);
FORCEPROP 2 LAST CDS_LIB pure_quanta
J 0
(-3675 2375);
DISPLAY INVISIBLE (-3675 2375);
FORCEPROP 1 LAST PATH I42
J 0
(-3625 2550);
DISPLAY 0.978723 (-3625 2550);
PAINT WHITE (-3625 2550);
DISPLAY INVISIBLE (-3625 2550);
FORCEPROP 0 LAST $SEC 1
J 0
(-3625 2550);
DISPLAY INVISIBLE (-3625 2550);
FORCEPROP 0 LAST CDS_SEC 1
J 0
(-3625 2550);
DISPLAY INVISIBLE (-3625 2550);
FORCEPROP 1 LASTPIN (-3675 2475) $PN 1
J 0
(-3670 2437);
DISPLAY 0.787234 (-3670 2437);
PAINT MONO (-3670 2437);
DISPLAY INVISIBLE (-3670 2437);
FORCEPROP 1 LASTPIN (-3675 2275) $PN 2
J 0
(-3670 2285);
DISPLAY 0.787234 (-3670 2285);
PAINT MONO (-3670 2285);
DISPLAY INVISIBLE (-3670 2285);
FORCEADD UNIVERSAL_GND..1
(-1600 -25);
FORCEPROP 3 LASTPIN (-1600 25) SIG_NAME GND\g
J 0
(-1590 35);
DISPLAY 0.659574 (-1590 35);
PAINT MONO (-1590 35);
DISPLAY INVISIBLE (-1590 35);
FORCEPROP 1 LAST HDL_POWER GND
J 1
(-1575 -100);
DISPLAY 0.872340 (-1575 -100);
PAINT GREEN (-1575 -100);
DISPLAY INVISIBLE (-1575 -100);
FORCEPROP 2 LAST CDS_LIB logical_power
J 0
(-1600 -25);
PAINT MONO (-1600 -25);
DISPLAY INVISIBLE (-1600 -25);
FORCEPROP 1 LAST PATH I43
J 0
(-1525 -25);
DISPLAY 0.872340 (-1525 -25);
PAINT AQUA (-1525 -25);
DISPLAY INVISIBLE (-1525 -25);
FORCEADD Q_CAP..1
(-1375 1600);
FORCEPROP 1 LAST PART_NUMBER TMP_QCH2336K1B12
J 0
(-1325 1450);
DISPLAY 0.617021 (-1325 1450);
PAINT BLUE (-1325 1450);
DISPLAY INVISIBLE (-1325 1450);
FORCEPROP 1 LAST PACK_TYPE 0402
J 0
(-1325 1500);
DISPLAY 0.617021 (-1325 1500);
PAINT SKYBLUE (-1325 1500);
FORCEPROP 1 LAST VALUE 3300PF
J 0
(-1325 1700);
DISPLAY 0.617021 (-1325 1700);
PAINT SKYBLUE (-1325 1700);
FORCEPROP 1 LAST VOLTAGE 50V
J 0
(-1325 1650);
DISPLAY 0.617021 (-1325 1650);
PAINT SKYBLUE (-1325 1650);
FORCEPROP 1 LAST TOLERANCE 10%
J 0
(-1325 1600);
DISPLAY 0.617021 (-1325 1600);
PAINT SKYBLUE (-1325 1600);
FORCEPROP 1 LAST MATERIAL X7R
J 0
(-1325 1550);
DISPLAY 0.617021 (-1325 1550);
PAINT SKYBLUE (-1325 1550);
FORCEPROP 1 LAST LOCATION PC297_P0_1
J 0
(-1325 1750);
DISPLAY 0.617021 (-1325 1750);
PAINT AQUA (-1325 1750);
FORCEPROP 1 LASTPIN (-1375 1700) $PN 1
J 0
(-1365 1680);
DISPLAY 0.617021 (-1365 1680);
PAINT MONO (-1365 1680);
FORCEPROP 1 LASTPIN (-1375 1500) $PN 2
J 0
(-1365 1480);
DISPLAY 0.617021 (-1365 1480);
PAINT MONO (-1365 1480);
FORCEPROP 2 LAST CDS_LIB pure_quanta
J 0
(-1375 1600);
DISPLAY INVISIBLE (-1375 1600);
FORCEPROP 1 LAST PATH I44
J 0
(-1325 1750);
DISPLAY 0.978723 (-1325 1750);
PAINT WHITE (-1325 1750);
DISPLAY INVISIBLE (-1325 1750);
FORCEPROP 1 LAST LOCATION PC297_P0_1
J 0
(-1325 1800);
DISPLAY 1.021277 (-1325 1800);
PAINT AQUA (-1325 1800);
DISPLAY INVISIBLE (-1325 1800);
FORCEPROP 0 LAST $SEC 1
J 0
(-1325 1800);
DISPLAY 0.680851 (-1325 1800);
PAINT MONO (-1325 1800);
DISPLAY INVISIBLE (-1325 1800);
FORCEPROP 0 LAST CDS_SEC 1
J 0
(-1325 1800);
DISPLAY 1.021277 (-1325 1800);
DISPLAY INVISIBLE (-1325 1800);
FORCEADD OFFPAGE..6
(-850 450);
FORCEPROP 2 LAST $XR0 269 
J 0
(-1130 450);
DISPLAY 0.638298 (-1130 450);
PAINT MONO (-1130 450);
FORCEPROP 1 LAST COMMENT_BODY TRUE
J 0
(-750 375);
DISPLAY 0.872340 (-750 375);
PAINT GREEN (-750 375);
DISPLAY INVISIBLE (-750 375);
FORCEPROP 1 LAST OFFPAGE TRUE
J 0
(-525 325);
DISPLAY 0.872340 (-525 325);
PAINT GREEN (-525 325);
DISPLAY INVISIBLE (-525 325);
FORCEPROP 2 LAST CDS_LIB standard
J 0
(-850 450);
DISPLAY INVISIBLE (-850 450);
FORCEPROP 2 LAST PATH I45
J 0
(-1125 500);
DISPLAY 1.021277 (-1125 500);
DISPLAY INVISIBLE (-1125 500);
FORCEADD Q_INDUCTOR4P_14..1
(175 575);
FORCEPROP 1 LAST PART_NUMBER CV+15^0TZ04
J 0
(-50 735);
DISPLAY 0.617021 (-50 735);
PAINT BLUE (-50 735);
DISPLAY INVISIBLE (-50 735);
FORCEPROP 1 LAST MATERIAL IND
J 0
(-50 785);
DISPLAY 0.617021 (-50 785);
PAINT SKYBLUE (-50 785);
FORCEPROP 2 LAST PART_TYPE SMLF
J 0
(-50 925);
DISPLAY 1.021277 (-50 925);
FORCEPROP 2 LAST VALUE 150NH
J 0
(-50 875);
DISPLAY 0.617021 (-50 875);
PAINT SKYBLUE (-50 875);
FORCEPROP 1 LAST LOCATION PL114
J 0
(-50 830);
DISPLAY 0.617021 (-50 830);
PAINT AQUA (-50 830);
FORCEPROP 2 LASTPIN (-225 700) $PN 1
J 2
(-235 710);
DISPLAY 0.617021 (-235 710);
PAINT MONO (-235 710);
FORCEPROP 2 LASTPIN (-225 450) $PN 2
J 2
(-235 460);
DISPLAY 0.617021 (-235 460);
PAINT MONO (-235 460);
FORCEPROP 2 LASTPIN (575 450) $PN 3
J 0
(585 460);
DISPLAY 0.617021 (585 460);
PAINT MONO (585 460);
FORCEPROP 2 LASTPIN (575 700) $PN 4
J 0
(585 710);
DISPLAY 0.617021 (585 710);
PAINT MONO (585 710);
FORCEPROP 1 LAST NEEDS_NO_SIZE TRUE
J 0
(175 575);
DISPLAY 0.468085 (175 575);
PAINT GREEN (175 575);
DISPLAY INVISIBLE (175 575);
FORCEPROP 2 LAST CDS_LIB pure_quanta
J 0
(175 575);
DISPLAY INVISIBLE (175 575);
FORCEPROP 2 LAST SEC_TYPE 
J 0
(-50 975);
DISPLAY 1.021277 (-50 975);
DISPLAY INVISIBLE (-50 975);
FORCEPROP 1 LAST PATH I46
J 0
(375 730);
DISPLAY 0.723404 (375 730);
PAINT GREEN (375 730);
DISPLAY INVISIBLE (375 730);
FORCEPROP 2 LAST SEC 1
J 0
(-50 975);
DISPLAY 0.680851 (-50 975);
PAINT MONO (-50 975);
DISPLAY INVISIBLE (-50 975);
FORCEADD Q_CAP..1
(-975 1600);
FORCEPROP 1 LAST PART_NUMBER CH5103KEB01
J 0
(-925 1450);
DISPLAY 0.617021 (-925 1450);
PAINT BLUE (-925 1450);
DISPLAY INVISIBLE (-925 1450);
FORCEPROP 1 LAST PACK_TYPE C0402
J 0
(-925 1500);
DISPLAY 0.617021 (-925 1500);
PAINT SKYBLUE (-925 1500);
FORCEPROP 1 LAST VOLTAGE 16V
J 0
(-925 1650);
DISPLAY 0.617021 (-925 1650);
PAINT SKYBLUE (-925 1650);
FORCEPROP 1 LAST VALUE 1UF
J 0
(-925 1700);
DISPLAY 0.617021 (-925 1700);
PAINT SKYBLUE (-925 1700);
FORCEPROP 1 LAST TOLERANCE 10%
J 0
(-925 1600);
DISPLAY 0.617021 (-925 1600);
PAINT SKYBLUE (-925 1600);
FORCEPROP 1 LAST MATERIAL X6S
J 0
(-925 1550);
DISPLAY 0.617021 (-925 1550);
PAINT SKYBLUE (-925 1550);
FORCEPROP 1 LAST LOCATION PC299_P0_1
J 0
(-925 1750);
DISPLAY 0.617021 (-925 1750);
PAINT AQUA (-925 1750);
FORCEPROP 1 LASTPIN (-975 1700) $PN 1
J 0
(-965 1680);
DISPLAY 0.617021 (-965 1680);
PAINT MONO (-965 1680);
FORCEPROP 1 LASTPIN (-975 1500) $PN 2
J 0
(-965 1480);
DISPLAY 0.617021 (-965 1480);
PAINT MONO (-965 1480);
FORCEPROP 2 LAST CDS_LIB pure_quanta
J 0
(-975 1600);
DISPLAY INVISIBLE (-975 1600);
FORCEPROP 1 LAST PATH I47
J 0
(-925 1750);
DISPLAY 0.978723 (-925 1750);
PAINT WHITE (-925 1750);
DISPLAY INVISIBLE (-925 1750);
FORCEPROP 1 LAST LOCATION PC299_P0_1
J 0
(-925 1800);
DISPLAY 1.021277 (-925 1800);
PAINT AQUA (-925 1800);
DISPLAY INVISIBLE (-925 1800);
FORCEPROP 0 LAST $SEC 1
J 0
(-925 1800);
DISPLAY 0.680851 (-925 1800);
PAINT MONO (-925 1800);
DISPLAY INVISIBLE (-925 1800);
FORCEPROP 0 LAST CDS_SEC 1
J 0
(-925 1800);
DISPLAY 1.021277 (-925 1800);
DISPLAY INVISIBLE (-925 1800);
FORCEADD Q_CAP..1
R 2
(-275 975);
FORCEPROP 1 LAST PART_NUMBER CH4106K1B01
J 2
(-325 900);
DISPLAY 0.617021 (-325 900);
PAINT BLUE (-325 900);
DISPLAY INVISIBLE (-325 900);
FORCEPROP 1 LAST VOLTAGE 50V
J 2
(-325 975);
DISPLAY 0.617021 (-325 975);
PAINT SKYBLUE (-325 975);
FORCEPROP 1 LAST TOLERANCE 10%
J 2
(-325 950);
DISPLAY 0.617021 (-325 950);
PAINT SKYBLUE (-325 950);
FORCEPROP 1 LAST MATERIAL X7R
J 2
(-325 925);
DISPLAY 0.617021 (-325 925);
PAINT SKYBLUE (-325 925);
FORCEPROP 1 LAST VALUE 100NF
J 2
(-325 1000);
DISPLAY 0.617021 (-325 1000);
PAINT SKYBLUE (-325 1000);
FORCEPROP 1 LAST PACK_TYPE C0402
J 2
(-325 875);
DISPLAY 0.617021 (-325 875);
PAINT SKYBLUE (-325 875);
FORCEPROP 1 LAST LOCATION PC301
J 2
(-325 1050);
DISPLAY 0.617021 (-325 1050);
PAINT AQUA (-325 1050);
FORCEPROP 1 LASTPIN (-275 1075) $PN 1
J 2
(-285 1055);
DISPLAY 0.617021 (-285 1055);
FORCEPROP 1 LASTPIN (-275 875) $PN 2
J 2
(-285 855);
DISPLAY 0.617021 (-285 855);
FORCEPROP 2 LAST CDS_LIB pure_quanta
J 2
(-275 975);
PAINT MONO (-275 975);
DISPLAY INVISIBLE (-275 975);
FORCEPROP 1 LAST PATH I48
J 2
(-325 1125);
DISPLAY 0.978723 (-325 1125);
PAINT WHITE (-325 1125);
DISPLAY INVISIBLE (-325 1125);
FORCEPROP 2 LAST $SEC 1
J 0
(-325 1175);
DISPLAY 0.680851 (-325 1175);
PAINT MONO (-325 1175);
DISPLAY INVISIBLE (-325 1175);
FORCEPROP 2 LAST CDS_SEC 1
J 0
(-325 1175);
DISPLAY 1.021277 (-325 1175);
DISPLAY INVISIBLE (-325 1175);
FORCEADD Q_CAP..1
(-575 1600);
FORCEPROP 1 LAST PART_NUMBER CH6223MEA01
J 0
(-525 1450);
DISPLAY 0.617021 (-525 1450);
PAINT BLUE (-525 1450);
DISPLAY INVISIBLE (-525 1450);
FORCEPROP 1 LAST TOLERANCE 20%
J 0
(-525 1600);
DISPLAY 0.617021 (-525 1600);
PAINT SKYBLUE (-525 1600);
FORCEPROP 1 LAST PACK_TYPE C0805
J 0
(-525 1500);
DISPLAY 0.617021 (-525 1500);
PAINT SKYBLUE (-525 1500);
FORCEPROP 1 LAST VOLTAGE 16V
J 0
(-525 1650);
DISPLAY 0.617021 (-525 1650);
PAINT SKYBLUE (-525 1650);
FORCEPROP 1 LAST MATERIAL X6S
J 0
(-525 1550);
DISPLAY 0.617021 (-525 1550);
PAINT SKYBLUE (-525 1550);
FORCEPROP 1 LAST VALUE 22UF
J 0
(-525 1700);
DISPLAY 0.617021 (-525 1700);
PAINT SKYBLUE (-525 1700);
FORCEPROP 1 LAST LOCATION PC303_P0_1
J 0
(-525 1750);
DISPLAY 0.617021 (-525 1750);
PAINT AQUA (-525 1750);
FORCEPROP 1 LASTPIN (-575 1700) $PN 1
J 0
(-565 1680);
DISPLAY 0.617021 (-565 1680);
PAINT MONO (-565 1680);
FORCEPROP 1 LASTPIN (-575 1500) $PN 2
J 0
(-565 1480);
DISPLAY 0.617021 (-565 1480);
PAINT MONO (-565 1480);
FORCEPROP 2 LAST CDS_LIB pure_quanta
J 0
(-575 1600);
DISPLAY INVISIBLE (-575 1600);
FORCEPROP 1 LAST PATH I49
J 0
(-525 1750);
DISPLAY 0.978723 (-525 1750);
PAINT WHITE (-525 1750);
DISPLAY INVISIBLE (-525 1750);
FORCEPROP 1 LAST LOCATION PC303_P0_1
J 0
(-525 1800);
DISPLAY 1.021277 (-525 1800);
PAINT AQUA (-525 1800);
DISPLAY INVISIBLE (-525 1800);
FORCEPROP 0 LAST $SEC 1
J 0
(-525 1800);
DISPLAY 0.680851 (-525 1800);
PAINT MONO (-525 1800);
DISPLAY INVISIBLE (-525 1800);
FORCEPROP 0 LAST CDS_SEC 1
J 0
(-525 1800);
DISPLAY 1.021277 (-525 1800);
DISPLAY INVISIBLE (-525 1800);
FORCEADD OFFPAGE..5
(-3650 -2625);
FORCEPROP 2 LAST $XR4 266 
J 0
(-3905 -2589);
DISPLAY 0.638298 (-3905 -2589);
PAINT MONO (-3905 -2589);
FORCEPROP 2 LAST $XR3 270 
J 0
(-4025 -2661);
DISPLAY 0.638298 (-4025 -2661);
PAINT MONO (-4025 -2661);
FORCEPROP 2 LAST $XR2 269 
J 0
(-3905 -2661);
DISPLAY 0.638298 (-3905 -2661);
PAINT MONO (-3905 -2661);
FORCEPROP 2 LAST $XR1 268 
J 0
(-4025 -2625);
DISPLAY 0.638298 (-4025 -2625);
PAINT MONO (-4025 -2625);
FORCEPROP 2 LAST $XR0 267 
J 0
(-3905 -2625);
DISPLAY 0.638298 (-3905 -2625);
PAINT MONO (-3905 -2625);
FORCEPROP 1 LAST COMMENT_BODY TRUE
J 0
(-3550 -2700);
DISPLAY 0.872340 (-3550 -2700);
PAINT GREEN (-3550 -2700);
DISPLAY INVISIBLE (-3550 -2700);
FORCEPROP 1 LAST OFFPAGE TRUE
J 0
(-3325 -2750);
DISPLAY 0.872340 (-3325 -2750);
PAINT GREEN (-3325 -2750);
DISPLAY INVISIBLE (-3325 -2750);
FORCEPROP 2 LAST CDS_LIB standard
J 0
(-3650 -2625);
DISPLAY INVISIBLE (-3650 -2625);
FORCEPROP 2 LAST PATH I5
J 0
(-3900 -2550);
DISPLAY 1.021277 (-3900 -2550);
DISPLAY INVISIBLE (-3900 -2550);
FORCEADD Q_CAP..1
(-175 1600);
FORCEPROP 1 LAST PART_NUMBER CH6223MEA01
J 0
(-125 1450);
DISPLAY 0.617021 (-125 1450);
PAINT BLUE (-125 1450);
DISPLAY INVISIBLE (-125 1450);
FORCEPROP 1 LAST TOLERANCE 20%
J 0
(-125 1600);
DISPLAY 0.617021 (-125 1600);
PAINT SKYBLUE (-125 1600);
FORCEPROP 1 LAST PACK_TYPE C0805
J 0
(-125 1500);
DISPLAY 0.617021 (-125 1500);
PAINT SKYBLUE (-125 1500);
FORCEPROP 1 LAST MATERIAL X6S
J 0
(-125 1550);
DISPLAY 0.617021 (-125 1550);
PAINT SKYBLUE (-125 1550);
FORCEPROP 1 LAST VOLTAGE 16V
J 0
(-125 1650);
DISPLAY 0.617021 (-125 1650);
PAINT SKYBLUE (-125 1650);
FORCEPROP 1 LAST VALUE 22UF
J 0
(-125 1700);
DISPLAY 0.617021 (-125 1700);
PAINT SKYBLUE (-125 1700);
FORCEPROP 1 LAST LOCATION PC305_P0_1
J 0
(-125 1750);
DISPLAY 0.617021 (-125 1750);
PAINT AQUA (-125 1750);
FORCEPROP 1 LASTPIN (-175 1700) $PN 1
J 0
(-165 1680);
DISPLAY 0.617021 (-165 1680);
PAINT MONO (-165 1680);
FORCEPROP 1 LASTPIN (-175 1500) $PN 2
J 0
(-165 1480);
DISPLAY 0.617021 (-165 1480);
PAINT MONO (-165 1480);
FORCEPROP 2 LAST CDS_LIB pure_quanta
J 0
(-175 1600);
DISPLAY INVISIBLE (-175 1600);
FORCEPROP 1 LAST PATH I50
J 0
(-125 1750);
DISPLAY 0.978723 (-125 1750);
PAINT WHITE (-125 1750);
DISPLAY INVISIBLE (-125 1750);
FORCEPROP 1 LAST LOCATION PC305_P0_1
J 0
(-125 1800);
DISPLAY 1.021277 (-125 1800);
PAINT AQUA (-125 1800);
DISPLAY INVISIBLE (-125 1800);
FORCEPROP 0 LAST $SEC 1
J 0
(-125 1800);
DISPLAY 0.680851 (-125 1800);
PAINT MONO (-125 1800);
DISPLAY INVISIBLE (-125 1800);
FORCEPROP 0 LAST CDS_SEC 1
J 0
(-125 1800);
DISPLAY 1.021277 (-125 1800);
DISPLAY INVISIBLE (-125 1800);
FORCEADD Q_RES..1
(25 -2675);
FORCEPROP 1 LAST PART_NUMBER CS00002JB13
J 0
(-100 -2625);
DISPLAY 0.617021 (-100 -2625);
PAINT BLUE (-100 -2625);
DISPLAY INVISIBLE (-100 -2625);
FORCEPROP 1 LAST WATTAGE 1/16W
J 2
(275 -2575);
DISPLAY 0.617021 (275 -2575);
PAINT SKYBLUE (275 -2575);
FORCEPROP 1 LAST PACK_TYPE 0402LF
J 0
(-100 -2575);
DISPLAY 0.617021 (-100 -2575);
PAINT SKYBLUE (-100 -2575);
FORCEPROP 1 LAST VALUE 0
J 2
(200 -2675);
DISPLAY 0.617021 (200 -2675);
PAINT SKYBLUE (200 -2675);
FORCEPROP 1 LAST MATERIAL CHIP
J 0
(300 -2675);
DISPLAY 0.617021 (300 -2675);
PAINT SKYBLUE (300 -2675);
FORCEPROP 1 LAST TOLERANCE 5%
J 0
(225 -2675);
DISPLAY 0.617021 (225 -2675);
PAINT SKYBLUE (225 -2675);
FORCEPROP 1 LAST LOCATION PR154
J 0
(-250 -2675);
DISPLAY 0.617021 (-250 -2675);
PAINT AQUA (-250 -2675);
FORCEPROP 1 LASTPIN (-75 -2675) $PN 1
J 0
(-63 -2663);
DISPLAY 0.617021 (-63 -2663);
PAINT MONO (-63 -2663);
FORCEPROP 1 LASTPIN (125 -2675) $PN 2
J 0
(87 -2663);
DISPLAY 0.617021 (87 -2663);
PAINT MONO (87 -2663);
FORCEPROP 2 LAST CDS_LIB pure_quanta
J 0
(25 -2675);
DISPLAY INVISIBLE (25 -2675);
FORCEPROP 1 LAST PATH I51
J 0
(-25 -2525);
DISPLAY 0.978723 (-25 -2525);
PAINT WHITE (-25 -2525);
DISPLAY INVISIBLE (-25 -2525);
FORCEPROP 0 LAST $SEC 1
J 0
(275 -2525);
DISPLAY 0.680851 (275 -2525);
PAINT MONO (275 -2525);
DISPLAY INVISIBLE (275 -2525);
FORCEPROP 0 LAST CDS_SEC 1
J 0
(275 -2525);
DISPLAY 1.021277 (275 -2525);
DISPLAY INVISIBLE (275 -2525);
FORCEADD OFFPAGE..3
(1200 -2375);
FORCEPROP 2 LAST $XR0 268 
J 0
(1414 -2375);
DISPLAY 0.638298 (1414 -2375);
PAINT MONO (1414 -2375);
FORCEPROP 1 LAST COMMENT_BODY TRUE
J 0
(1150 -2475);
DISPLAY 0.872340 (1150 -2475);
PAINT GREEN (1150 -2475);
DISPLAY INVISIBLE (1150 -2475);
FORCEPROP 1 LAST OFFPAGE TRUE
J 0
(1525 -2500);
DISPLAY 0.872340 (1525 -2500);
PAINT GREEN (1525 -2500);
DISPLAY INVISIBLE (1525 -2500);
FORCEPROP 2 LAST CDS_LIB standard
J 0
(1200 -2375);
DISPLAY INVISIBLE (1200 -2375);
FORCEPROP 2 LAST PATH I52
J 0
(1425 -2325);
DISPLAY 1.021277 (1425 -2325);
DISPLAY INVISIBLE (1425 -2325);
FORCEADD UNIVERSAL_GND..1
(325 -1650);
FORCEPROP 3 LASTPIN (325 -1600) SIG_NAME GND\g
J 0
(335 -1590);
DISPLAY 0.659574 (335 -1590);
PAINT MONO (335 -1590);
DISPLAY INVISIBLE (335 -1590);
FORCEPROP 1 LAST HDL_POWER GND
J 1
(350 -1725);
DISPLAY 0.872340 (350 -1725);
PAINT GREEN (350 -1725);
DISPLAY INVISIBLE (350 -1725);
FORCEPROP 2 LAST CDS_LIB logical_power
J 0
(325 -1650);
PAINT MONO (325 -1650);
DISPLAY INVISIBLE (325 -1650);
FORCEPROP 1 LAST PATH I53
J 0
(400 -1650);
DISPLAY 0.872340 (400 -1650);
PAINT AQUA (400 -1650);
DISPLAY INVISIBLE (400 -1650);
FORCEADD Q_CAP..1
(100 -1225);
FORCEPROP 1 LAST PART_NUMBER CH6223MEA01
J 0
(150 -1375);
DISPLAY 0.617021 (150 -1375);
PAINT BLUE (150 -1375);
DISPLAY INVISIBLE (150 -1375);
FORCEPROP 1 LAST TOLERANCE 20%
J 0
(150 -1225);
DISPLAY 0.617021 (150 -1225);
PAINT SKYBLUE (150 -1225);
FORCEPROP 1 LAST PACK_TYPE C0805
J 0
(150 -1325);
DISPLAY 0.617021 (150 -1325);
PAINT SKYBLUE (150 -1325);
FORCEPROP 1 LAST VOLTAGE 16V
J 0
(150 -1175);
DISPLAY 0.617021 (150 -1175);
PAINT SKYBLUE (150 -1175);
FORCEPROP 1 LAST VALUE 22UF
J 0
(150 -1125);
DISPLAY 0.617021 (150 -1125);
PAINT SKYBLUE (150 -1125);
FORCEPROP 1 LAST MATERIAL X6S
J 0
(150 -1275);
DISPLAY 0.617021 (150 -1275);
PAINT SKYBLUE (150 -1275);
FORCEPROP 1 LAST LOCATION PC306_P0_2
J 0
(150 -1075);
DISPLAY 0.617021 (150 -1075);
PAINT AQUA (150 -1075);
FORCEPROP 1 LASTPIN (100 -1125) $PN 1
J 0
(110 -1145);
DISPLAY 0.617021 (110 -1145);
PAINT MONO (110 -1145);
FORCEPROP 1 LASTPIN (100 -1325) $PN 2
J 0
(110 -1345);
DISPLAY 0.617021 (110 -1345);
PAINT MONO (110 -1345);
FORCEPROP 2 LAST CDS_LIB pure_quanta
J 0
(100 -1225);
DISPLAY INVISIBLE (100 -1225);
FORCEPROP 1 LAST PATH I54
J 0
(150 -1075);
DISPLAY 0.978723 (150 -1075);
PAINT WHITE (150 -1075);
DISPLAY INVISIBLE (150 -1075);
FORCEPROP 1 LAST LOCATION PC306_P0_2
J 0
(150 -1025);
DISPLAY 1.021277 (150 -1025);
PAINT AQUA (150 -1025);
DISPLAY INVISIBLE (150 -1025);
FORCEPROP 0 LAST $SEC 1
J 0
(150 -1025);
DISPLAY 0.680851 (150 -1025);
PAINT MONO (150 -1025);
DISPLAY INVISIBLE (150 -1025);
FORCEPROP 0 LAST CDS_SEC 1
J 0
(150 -1025);
DISPLAY 1.021277 (150 -1025);
DISPLAY INVISIBLE (150 -1025);
FORCEADD VCC15..1
(325 -850);
FORCEPROP 3 LASTPIN (325 -900) SIG_NAME SW_P12V_PVCCIN_CPU0_FLT\g
J 0
(335 -890);
DISPLAY 0.659574 (335 -890);
PAINT MONO (335 -890);
DISPLAY INVISIBLE (335 -890);
FORCEPROP 1 LAST HDL_POWER SW_P12V_PVCCIN_CPU0_FLT
J 1
(375 -800);
DISPLAY 0.617021 (375 -800);
PAINT GREEN (375 -800);
FORCEPROP 2 LAST CDS_LIB logical_power
J 0
(325 -850);
DISPLAY INVISIBLE (325 -850);
FORCEPROP 1 LAST PATH I55
J 0
(375 -825);
DISPLAY 0.872340 (375 -825);
PAINT AQUA (375 -825);
DISPLAY INVISIBLE (375 -825);
FORCEADD Q_CAPP..1
(1950 -525);
FORCEPROP 1 LAST PART_NUMBER CC7560JMD16
J 0
(2000 -700);
DISPLAY 0.617021 (2000 -700);
PAINT BLUE (2000 -700);
DISPLAY INVISIBLE (2000 -700);
FORCEPROP 1 LAST TOLERANCE 20%
J 0
(2000 -500);
DISPLAY 0.617021 (2000 -500);
PAINT SKYBLUE (2000 -500);
FORCEPROP 1 LAST VOLTAGE 2.5V
J 0
(2000 -550);
DISPLAY 0.617021 (2000 -550);
PAINT SKYBLUE (2000 -550);
FORCEPROP 1 LAST MATERIAL OSCON
J 0
(2000 -600);
DISPLAY 0.617021 (2000 -600);
PAINT SKYBLUE (2000 -600);
FORCEPROP 1 LAST PACK_TYPE THLF
J 0
(2000 -650);
DISPLAY 0.617021 (2000 -650);
PAINT SKYBLUE (2000 -650);
FORCEPROP 1 LAST VALUE 560UF
J 0
(2000 -450);
DISPLAY 0.617021 (2000 -450);
PAINT SKYBLUE (2000 -450);
FORCEPROP 1 LAST LOCATION PC16
J 0
(2000 -400);
DISPLAY 0.617021 (2000 -400);
PAINT AQUA (2000 -400);
FORCEPROP 1 LASTPIN (1950 -425) $PN 1
J 0
(1960 -440);
DISPLAY 0.617021 (1960 -440);
PAINT MONO (1960 -440);
FORCEPROP 1 LASTPIN (1950 -625) $PN 2
J 0
(1960 -640);
DISPLAY 0.617021 (1960 -640);
PAINT MONO (1960 -640);
FORCEPROP 2 LAST CDS_LIB pure_quanta
J 0
(1950 -525);
DISPLAY INVISIBLE (1950 -525);
FORCEPROP 1 LAST PATH I56
J 0
(2000 -375);
DISPLAY 0.978723 (2000 -375);
DISPLAY INVISIBLE (2000 -375);
FORCEPROP 0 LAST $SEC 1
J 0
(2000 -375);
DISPLAY 0.680851 (2000 -375);
PAINT MONO (2000 -375);
DISPLAY INVISIBLE (2000 -375);
FORCEPROP 0 LAST CDS_SEC 1
J 0
(2000 -375);
DISPLAY 1.021277 (2000 -375);
DISPLAY INVISIBLE (2000 -375);
FORCEADD Q_CAP..1
(2900 -2450);
FORCEPROP 1 LAST PART_NUMBER CH622KMEA03
J 0
(2950 -2625);
DISPLAY 0.617021 (2950 -2625);
PAINT BLUE (2950 -2625);
DISPLAY INVISIBLE (2950 -2625);
FORCEPROP 1 LAST TOLERANCE 20%
J 0
(2950 -2475);
DISPLAY 0.617021 (2950 -2475);
PAINT SKYBLUE (2950 -2475);
FORCEPROP 1 LAST VOLTAGE 4V
J 0
(2950 -2425);
DISPLAY 0.617021 (2950 -2425);
PAINT SKYBLUE (2950 -2425);
FORCEPROP 1 LAST VALUE 22UF
J 0
(2950 -2375);
DISPLAY 0.617021 (2950 -2375);
PAINT SKYBLUE (2950 -2375);
FORCEPROP 1 LAST MATERIAL X6S
J 0
(2950 -2525);
DISPLAY 0.617021 (2950 -2525);
PAINT SKYBLUE (2950 -2525);
FORCEPROP 1 LAST PACK_TYPE C0805
J 0
(2950 -2575);
DISPLAY 0.617021 (2950 -2575);
PAINT SKYBLUE (2950 -2575);
FORCEPROP 1 LAST LOCATION PC311_P0_2
J 0
(2950 -2325);
DISPLAY 0.617021 (2950 -2325);
PAINT AQUA (2950 -2325);
FORCEPROP 1 LASTPIN (2900 -2350) $PN 1
J 0
(2910 -2370);
DISPLAY 0.617021 (2910 -2370);
PAINT MONO (2910 -2370);
FORCEPROP 1 LASTPIN (2900 -2550) $PN 2
J 0
(2910 -2570);
DISPLAY 0.617021 (2910 -2570);
PAINT MONO (2910 -2570);
FORCEPROP 2 LAST CDS_LIB pure_quanta
J 0
(2900 -2450);
DISPLAY INVISIBLE (2900 -2450);
FORCEPROP 1 LAST PATH I57
J 0
(2950 -2300);
DISPLAY 0.978723 (2950 -2300);
PAINT WHITE (2950 -2300);
DISPLAY INVISIBLE (2950 -2300);
FORCEPROP 1 LAST LOCATION PC311_P0_2
J 0
(2950 -2275);
DISPLAY 1.021277 (2950 -2275);
PAINT AQUA (2950 -2275);
DISPLAY INVISIBLE (2950 -2275);
FORCEPROP 0 LAST $SEC 1
J 0
(2950 -2275);
DISPLAY 0.680851 (2950 -2275);
PAINT MONO (2950 -2275);
DISPLAY INVISIBLE (2950 -2275);
FORCEPROP 0 LAST CDS_SEC 1
J 0
(2950 -2275);
DISPLAY 1.021277 (2950 -2275);
DISPLAY INVISIBLE (2950 -2275);
FORCEADD Q_CAP..1
(3325 -2450);
FORCEPROP 1 LAST PART_NUMBER CH622KMEA03
J 0
(3375 -2625);
DISPLAY 0.617021 (3375 -2625);
PAINT BLUE (3375 -2625);
DISPLAY INVISIBLE (3375 -2625);
FORCEPROP 1 LAST TOLERANCE 20%
J 0
(3375 -2475);
DISPLAY 0.617021 (3375 -2475);
PAINT SKYBLUE (3375 -2475);
FORCEPROP 1 LAST PACK_TYPE C0805
J 0
(3375 -2575);
DISPLAY 0.617021 (3375 -2575);
PAINT SKYBLUE (3375 -2575);
FORCEPROP 1 LAST MATERIAL X6S
J 0
(3375 -2525);
DISPLAY 0.617021 (3375 -2525);
PAINT SKYBLUE (3375 -2525);
FORCEPROP 1 LAST VALUE 22UF
J 0
(3375 -2375);
DISPLAY 0.617021 (3375 -2375);
PAINT SKYBLUE (3375 -2375);
FORCEPROP 1 LAST VOLTAGE 4V
J 0
(3375 -2425);
DISPLAY 0.617021 (3375 -2425);
PAINT SKYBLUE (3375 -2425);
FORCEPROP 1 LAST LOCATION PC313_P0_2
J 0
(3375 -2325);
DISPLAY 0.617021 (3375 -2325);
PAINT AQUA (3375 -2325);
FORCEPROP 1 LASTPIN (3325 -2350) $PN 1
J 0
(3335 -2370);
DISPLAY 0.617021 (3335 -2370);
PAINT MONO (3335 -2370);
FORCEPROP 1 LASTPIN (3325 -2550) $PN 2
J 0
(3335 -2570);
DISPLAY 0.617021 (3335 -2570);
PAINT MONO (3335 -2570);
FORCEPROP 2 LAST CDS_LIB pure_quanta
J 0
(3325 -2450);
DISPLAY INVISIBLE (3325 -2450);
FORCEPROP 1 LAST PATH I58
J 0
(3375 -2300);
DISPLAY 0.978723 (3375 -2300);
PAINT WHITE (3375 -2300);
DISPLAY INVISIBLE (3375 -2300);
FORCEPROP 1 LAST LOCATION PC313_P0_2
J 0
(3375 -2275);
DISPLAY 1.021277 (3375 -2275);
PAINT AQUA (3375 -2275);
DISPLAY INVISIBLE (3375 -2275);
FORCEPROP 0 LAST $SEC 1
J 0
(3375 -2275);
DISPLAY 0.680851 (3375 -2275);
PAINT MONO (3375 -2275);
DISPLAY INVISIBLE (3375 -2275);
FORCEPROP 0 LAST CDS_SEC 1
J 0
(3375 -2275);
DISPLAY 1.021277 (3375 -2275);
DISPLAY INVISIBLE (3375 -2275);
FORCEADD Q_RES..2
(3725 -2450);
FORCEPROP 1 LAST PART_NUMBER CS14992FB06
J 0
(3765 -2575);
DISPLAY 0.617021 (3765 -2575);
PAINT BLUE (3765 -2575);
DISPLAY INVISIBLE (3765 -2575);
FORCEPROP 1 LAST MATERIAL CHIP
J 0
(3765 -2525);
DISPLAY 0.617021 (3765 -2525);
PAINT SKYBLUE (3765 -2525);
FORCEPROP 1 LAST WATTAGE 1/16W
J 0
(3765 -2475);
DISPLAY 0.617021 (3765 -2475);
PAINT SKYBLUE (3765 -2475);
FORCEPROP 1 LAST TOLERANCE 1%
J 0
(3770 -2425);
DISPLAY 0.617021 (3770 -2425);
PAINT SKYBLUE (3770 -2425);
FORCEPROP 1 LAST VALUE 499
J 0
(3770 -2375);
DISPLAY 0.617021 (3770 -2375);
PAINT SKYBLUE (3770 -2375);
FORCEPROP 1 LAST PACK_TYPE 0402LF
J 0
(3765 -2625);
DISPLAY 0.617021 (3765 -2625);
PAINT SKYBLUE (3765 -2625);
FORCEPROP 1 LAST LOCATION PR4219
J 0
(3770 -2325);
DISPLAY 0.617021 (3770 -2325);
PAINT AQUA (3770 -2325);
FORCEPROP 1 LASTPIN (3725 -2350) $PN 1
J 0
(3730 -2388);
DISPLAY 0.787234 (3730 -2388);
PAINT MONO (3730 -2388);
FORCEPROP 1 LASTPIN (3725 -2550) $PN 2
J 0
(3730 -2540);
DISPLAY 0.787234 (3730 -2540);
PAINT MONO (3730 -2540);
FORCEPROP 2 LAST CDS_LIB pure_quanta
J 0
(3725 -2450);
DISPLAY INVISIBLE (3725 -2450);
FORCEPROP 2 LAST BOM_COST VR_PCH
J 0
(3775 -2275);
DISPLAY 0.680851 (3775 -2275);
DISPLAY INVISIBLE (3775 -2275);
FORCEPROP 1 LAST PATH I59
J 0
(3775 -2275);
DISPLAY 0.978723 (3775 -2275);
PAINT WHITE (3775 -2275);
DISPLAY INVISIBLE (3775 -2275);
FORCEPROP 0 LAST $SEC 1
J 0
(3775 -2275);
DISPLAY 0.680851 (3775 -2275);
PAINT MONO (3775 -2275);
DISPLAY INVISIBLE (3775 -2275);
FORCEPROP 0 LAST CDS_SEC 1
J 0
(3775 -2275);
DISPLAY 1.021277 (3775 -2275);
DISPLAY INVISIBLE (3775 -2275);
FORCEADD ISL99390FRZTR5935..1
(-2275 -2125);
FORCEPROP 1 LAST PART_NUMBER AL099390004
J 0
(-2575 -1325);
DISPLAY 0.617021 (-2575 -1325);
PAINT BLUE (-2575 -1325);
DISPLAY INVISIBLE (-2575 -1325);
FORCEPROP 2 LAST VALUE ISL99390FRZ-TR5935
J 0
(-2575 -1175);
DISPLAY 0.617021 (-2575 -1175);
PAINT SKYBLUE (-2575 -1175);
FORCEPROP 1 LAST MATERIAL IC
J 0
(-2575 -1400);
DISPLAY 0.617021 (-2575 -1400);
PAINT SKYBLUE (-2575 -1400);
FORCEPROP 2 LAST PART_TYPE SMLF
J 0
(-2575 -1125);
DISPLAY 0.808511 (-2575 -1125);
FORCEPROP 1 LAST LOCATION PU12_P0_2
J 0
(-2575 -1250);
DISPLAY 0.617021 (-2575 -1250);
PAINT AQUA (-2575 -1250);
FORCEPROP 2 LASTPIN (-1875 -2575) $PN 2
J 0
(-1865 -2565);
DISPLAY 0.617021 (-1865 -2565);
PAINT MONO (-1865 -2565);
FORCEPROP 2 LASTPIN (-1875 -1775) $PN 33
J 0
(-1865 -1765);
DISPLAY 0.617021 (-1865 -1765);
PAINT MONO (-1865 -1765);
FORCEPROP 2 LASTPIN (-2725 -2375) $PN 31
J 2
(-2735 -2365);
DISPLAY 0.617021 (-2735 -2365);
PAINT MONO (-2735 -2365);
FORCEPROP 2 LASTPIN (-2725 -1975) $PN 35
J 2
(-2735 -1965);
DISPLAY 0.617021 (-2735 -1965);
PAINT MONO (-2735 -1965);
FORCEPROP 2 LASTPIN (-1875 -2425) $PN 6
J 0
(-1865 -2415);
DISPLAY 0.617021 (-1865 -2415);
PAINT MONO (-1865 -2415);
FORCEPROP 2 LASTPIN (-1875 -2475) $PN 41
J 0
(-1865 -2465);
DISPLAY 0.617021 (-1865 -2465);
PAINT MONO (-1865 -2465);
FORCEPROP 2 LASTPIN (-2725 -2125) $PN 38
J 2
(-2735 -2115);
DISPLAY 0.617021 (-2735 -2115);
PAINT MONO (-2735 -2115);
FORCEPROP 2 LASTPIN (-2725 -2425) $PN 37
J 2
(-2735 -2415);
DISPLAY 0.617021 (-2735 -2415);
PAINT MONO (-2735 -2415);
FORCEPROP 2 LASTPIN (-1875 -2625) $PN 5
J 0
(-1865 -2615);
DISPLAY 0.617021 (-1865 -2615);
PAINT MONO (-1865 -2615);
FORCEPROP 2 LASTPIN (-1875 -2675) $PN 7_9-20_24
J 0
(-1865 -2665);
DISPLAY 0.617021 (-1865 -2665);
PAINT MONO (-1865 -2665);
FORCEPROP 2 LASTPIN (-1875 -2725) $PN 40
J 0
(-1865 -2715);
DISPLAY 0.617021 (-1865 -2715);
PAINT MONO (-1865 -2715);
FORCEPROP 2 LASTPIN (-1875 -2025) $PN 32
J 0
(-1865 -2015);
DISPLAY 0.617021 (-1865 -2015);
PAINT MONO (-1865 -2015);
FORCEPROP 2 LASTPIN (-2725 -1475) $PN 4
J 2
(-2735 -1465);
DISPLAY 0.617021 (-2735 -1465);
PAINT MONO (-2735 -1465);
FORCEPROP 2 LASTPIN (-2725 -2725) $PN 34
J 2
(-2735 -2715);
DISPLAY 0.617021 (-2735 -2715);
PAINT MONO (-2735 -2715);
FORCEPROP 2 LASTPIN (-2725 -2225) $PN 39
J 2
(-2735 -2215);
DISPLAY 0.617021 (-2735 -2215);
PAINT MONO (-2735 -2215);
FORCEPROP 2 LASTPIN (-1875 -2125) $PN 10_19
J 0
(-1865 -2115);
DISPLAY 0.617021 (-1865 -2115);
PAINT MONO (-1865 -2115);
FORCEPROP 2 LASTPIN (-2725 -2625) $PN 36
J 2
(-2735 -2615);
DISPLAY 0.617021 (-2735 -2615);
PAINT MONO (-2735 -2615);
FORCEPROP 2 LASTPIN (-2725 -1775) $PN 3
J 2
(-2735 -1765);
DISPLAY 0.617021 (-2735 -1765);
PAINT MONO (-2735 -1765);
FORCEPROP 2 LASTPIN (-1875 -1475) $PN 25_29
J 0
(-1865 -1465);
DISPLAY 0.617021 (-1865 -1465);
PAINT MONO (-1865 -1465);
FORCEPROP 2 LASTPIN (-1875 -1525) $PN 30
J 0
(-1865 -1515);
DISPLAY 0.617021 (-1865 -1515);
PAINT MONO (-1865 -1515);
FORCEPROP 2 LASTPIN (-1875 -2375) $PN 1
J 0
(-1865 -2365);
DISPLAY 0.617021 (-1865 -2365);
PAINT MONO (-1865 -2365);
FORCEPROP 1 LAST NEEDS_NO_SIZE TRUE
J 0
(-2275 -2125);
DISPLAY 0.723404 (-2275 -2125);
PAINT GREEN (-2275 -2125);
DISPLAY INVISIBLE (-2275 -2125);
FORCEPROP 1 LAST CDS_LMAN_SYM_OUTLINE -300,700,250,-650
J 0
(-2275 -2125);
DISPLAY 0.468085 (-2275 -2125);
PAINT GREEN (-2275 -2125);
DISPLAY INVISIBLE (-2275 -2125);
FORCEPROP 2 LAST CDS_LIB pure_quanta
J 0
(-2275 -2125);
DISPLAY INVISIBLE (-2275 -2125);
FORCEPROP 2 LAST SEC_TYPE 
J 0
(-2575 -1075);
DISPLAY 1.021277 (-2575 -1075);
DISPLAY INVISIBLE (-2575 -1075);
FORCEPROP 1 LAST PATH I6
J 0
(-2275 -2125);
DISPLAY 0.723404 (-2275 -2125);
PAINT GREEN (-2275 -2125);
DISPLAY INVISIBLE (-2275 -2125);
FORCEPROP 2 LAST SEC 1
J 0
(-2575 -1075);
DISPLAY 0.680851 (-2575 -1075);
PAINT MONO (-2575 -1075);
DISPLAY INVISIBLE (-2575 -1075);
FORCEADD Q_CAPP..1
(2525 -1425);
FORCEPROP 1 LAST PART_NUMBER CH733LY8802
J 0
(2575 -1575);
DISPLAY 0.617021 (2575 -1575);
PAINT BLUE (2575 -1575);
DISPLAY INVISIBLE (2575 -1575);
FORCEPROP 1 LAST VOLTAGE 2.5V
J 0
(2575 -1425);
DISPLAY 0.617021 (2575 -1425);
PAINT SKYBLUE (2575 -1425);
FORCEPROP 1 LAST MATERIAL EMPTY
J 0
(2575 -1475);
DISPLAY 0.617021 (2575 -1475);
PAINT RED (2575 -1475);
FORCEPROP 1 LAST PACK_TYPE SMLF
J 0
(2575 -1525);
DISPLAY 0.617021 (2575 -1525);
PAINT SKYBLUE (2575 -1525);
FORCEPROP 1 LAST TOLERANCE +10/-35%
J 0
(2575 -1375);
DISPLAY 0.617021 (2575 -1375);
PAINT SKYBLUE (2575 -1375);
FORCEPROP 1 LAST VALUE 330UF
J 0
(2575 -1325);
DISPLAY 0.617021 (2575 -1325);
PAINT SKYBLUE (2575 -1325);
FORCEPROP 1 LAST LOCATION PC2336
J 0
(2575 -1275);
DISPLAY 0.617021 (2575 -1275);
PAINT AQUA (2575 -1275);
FORCEPROP 1 LASTPIN (2525 -1325) $PN 1
J 0
(2535 -1340);
DISPLAY 0.617021 (2535 -1340);
PAINT MONO (2535 -1340);
FORCEPROP 1 LASTPIN (2525 -1525) $PN 2
J 0
(2535 -1540);
DISPLAY 0.617021 (2535 -1540);
PAINT MONO (2535 -1540);
FORCEPROP 2 LAST CDS_LIB pure_quanta
J 0
(2525 -1425);
DISPLAY INVISIBLE (2525 -1425);
FORCEPROP 1 LAST PATH I60
J 0
(2575 -1275);
DISPLAY 0.978723 (2575 -1275);
DISPLAY INVISIBLE (2575 -1275);
FORCEPROP 0 LAST $SEC 1
J 0
(2575 -1225);
DISPLAY 0.680851 (2575 -1225);
PAINT MONO (2575 -1225);
DISPLAY INVISIBLE (2575 -1225);
FORCEPROP 0 LAST CDS_SEC 1
J 0
(2575 -1225);
DISPLAY 1.021277 (2575 -1225);
DISPLAY INVISIBLE (2575 -1225);
FORCEADD Q_CAPP..1
(2425 -550);
FORCEPROP 1 LAST PART_NUMBER CC7560JMD16
J 0
(2475 -700);
DISPLAY 0.617021 (2475 -700);
PAINT BLUE (2475 -700);
DISPLAY INVISIBLE (2475 -700);
FORCEPROP 1 LAST VALUE 560UF
J 0
(2475 -450);
DISPLAY 0.617021 (2475 -450);
PAINT SKYBLUE (2475 -450);
FORCEPROP 1 LAST MATERIAL OSCON
J 0
(2475 -600);
DISPLAY 0.617021 (2475 -600);
PAINT SKYBLUE (2475 -600);
FORCEPROP 1 LAST TOLERANCE 20%
J 0
(2475 -500);
DISPLAY 0.617021 (2475 -500);
PAINT SKYBLUE (2475 -500);
FORCEPROP 1 LAST VOLTAGE 2.5V
J 0
(2475 -550);
DISPLAY 0.617021 (2475 -550);
PAINT SKYBLUE (2475 -550);
FORCEPROP 1 LAST PACK_TYPE THLF
J 0
(2475 -650);
DISPLAY 0.617021 (2475 -650);
PAINT SKYBLUE (2475 -650);
FORCEPROP 1 LAST LOCATION PC316
J 0
(2475 -400);
DISPLAY 0.617021 (2475 -400);
PAINT AQUA (2475 -400);
FORCEPROP 1 LASTPIN (2425 -450) $PN 1
J 0
(2435 -465);
DISPLAY 0.617021 (2435 -465);
PAINT MONO (2435 -465);
FORCEPROP 1 LASTPIN (2425 -650) $PN 2
J 0
(2435 -665);
DISPLAY 0.617021 (2435 -665);
PAINT MONO (2435 -665);
FORCEPROP 2 LAST CDS_LIB pure_quanta
J 0
(2425 -550);
DISPLAY INVISIBLE (2425 -550);
FORCEPROP 1 LAST PATH I61
J 0
(2475 -400);
DISPLAY 0.978723 (2475 -400);
DISPLAY INVISIBLE (2475 -400);
FORCEPROP 1 LAST LOCATION PC316
J 0
(2475 -350);
DISPLAY 1.021277 (2475 -350);
PAINT AQUA (2475 -350);
DISPLAY INVISIBLE (2475 -350);
FORCEPROP 0 LAST $SEC 1
J 0
(2475 -350);
DISPLAY 0.680851 (2475 -350);
PAINT MONO (2475 -350);
DISPLAY INVISIBLE (2475 -350);
FORCEPROP 0 LAST CDS_SEC 1
J 0
(2475 -350);
DISPLAY 1.021277 (2475 -350);
DISPLAY INVISIBLE (2475 -350);
FORCEADD Q_CAPP..1
(2950 -550);
FORCEPROP 1 LAST PART_NUMBER CC7560JMD16
J 0
(3000 -700);
DISPLAY 0.617021 (3000 -700);
PAINT BLUE (3000 -700);
DISPLAY INVISIBLE (3000 -700);
FORCEPROP 1 LAST PACK_TYPE THLF
J 0
(3000 -650);
DISPLAY 0.617021 (3000 -650);
PAINT SKYBLUE (3000 -650);
FORCEPROP 1 LAST MATERIAL OSCON
J 0
(3000 -600);
DISPLAY 0.617021 (3000 -600);
PAINT SKYBLUE (3000 -600);
FORCEPROP 1 LAST VALUE 560UF
J 0
(3000 -450);
DISPLAY 0.617021 (3000 -450);
PAINT SKYBLUE (3000 -450);
FORCEPROP 1 LAST TOLERANCE 20%
J 0
(3000 -500);
DISPLAY 0.617021 (3000 -500);
PAINT SKYBLUE (3000 -500);
FORCEPROP 1 LAST VOLTAGE 2.5V
J 0
(3000 -550);
DISPLAY 0.617021 (3000 -550);
PAINT SKYBLUE (3000 -550);
FORCEPROP 1 LAST LOCATION PC319
J 0
(3000 -400);
DISPLAY 0.617021 (3000 -400);
PAINT AQUA (3000 -400);
FORCEPROP 1 LASTPIN (2950 -450) $PN 1
J 0
(2960 -465);
DISPLAY 0.617021 (2960 -465);
PAINT MONO (2960 -465);
FORCEPROP 1 LASTPIN (2950 -650) $PN 2
J 0
(2960 -665);
DISPLAY 0.617021 (2960 -665);
PAINT MONO (2960 -665);
FORCEPROP 2 LAST CDS_LIB pure_quanta
J 0
(2950 -550);
DISPLAY INVISIBLE (2950 -550);
FORCEPROP 1 LAST PATH I62
J 0
(3000 -400);
DISPLAY 0.978723 (3000 -400);
DISPLAY INVISIBLE (3000 -400);
FORCEPROP 1 LAST LOCATION PC319
J 0
(3000 -350);
DISPLAY 1.021277 (3000 -350);
PAINT AQUA (3000 -350);
DISPLAY INVISIBLE (3000 -350);
FORCEPROP 0 LAST $SEC 1
J 0
(3000 -350);
DISPLAY 0.680851 (3000 -350);
PAINT MONO (3000 -350);
DISPLAY INVISIBLE (3000 -350);
FORCEPROP 0 LAST CDS_SEC 1
J 0
(3000 -350);
DISPLAY 1.021277 (3000 -350);
DISPLAY INVISIBLE (3000 -350);
FORCEADD Q_CAPP..1
(3025 -1400);
FORCEPROP 1 LAST PART_NUMBER CH733LY8802
J 0
(3075 -1575);
DISPLAY 0.617021 (3075 -1575);
PAINT BLUE (3075 -1575);
DISPLAY INVISIBLE (3075 -1575);
FORCEPROP 1 LAST VOLTAGE 2.5V
J 0
(3075 -1425);
DISPLAY 0.617021 (3075 -1425);
PAINT SKYBLUE (3075 -1425);
FORCEPROP 1 LAST TOLERANCE +10/-35%
J 0
(3075 -1375);
DISPLAY 0.617021 (3075 -1375);
PAINT SKYBLUE (3075 -1375);
FORCEPROP 1 LAST VALUE 330UF
J 0
(3075 -1325);
DISPLAY 0.617021 (3075 -1325);
PAINT SKYBLUE (3075 -1325);
FORCEPROP 1 LAST PACK_TYPE SMLF
J 0
(3075 -1525);
DISPLAY 0.617021 (3075 -1525);
PAINT SKYBLUE (3075 -1525);
FORCEPROP 1 LAST MATERIAL EMPTY
J 0
(3075 -1475);
DISPLAY 0.617021 (3075 -1475);
PAINT RED (3075 -1475);
FORCEPROP 1 LAST LOCATION PC1920
J 0
(3075 -1275);
DISPLAY 0.617021 (3075 -1275);
PAINT AQUA (3075 -1275);
FORCEPROP 1 LASTPIN (3025 -1300) $PN 1
J 0
(3035 -1315);
DISPLAY 0.617021 (3035 -1315);
FORCEPROP 1 LASTPIN (3025 -1500) $PN 2
J 0
(3035 -1515);
DISPLAY 0.617021 (3035 -1515);
FORCEPROP 2 LAST CDS_LIB pure_quanta
J 0
(3025 -1400);
PAINT MONO (3025 -1400);
DISPLAY INVISIBLE (3025 -1400);
FORCEPROP 1 LAST PATH I63
J 0
(3075 -1250);
DISPLAY 0.978723 (3075 -1250);
DISPLAY INVISIBLE (3075 -1250);
FORCEPROP 2 LAST $SEC 1
J 0
(3075 -1200);
DISPLAY 0.680851 (3075 -1200);
PAINT MONO (3075 -1200);
DISPLAY INVISIBLE (3075 -1200);
FORCEPROP 2 LAST CDS_SEC 1
J 0
(3075 -1200);
DISPLAY 1.021277 (3075 -1200);
DISPLAY INVISIBLE (3075 -1200);
FORCEADD Q_CAPP..1
(3475 -1425);
FORCEPROP 1 LAST PART_NUMBER CH733LY8802
J 0
(3525 -1575);
DISPLAY 0.617021 (3525 -1575);
PAINT BLUE (3525 -1575);
DISPLAY INVISIBLE (3525 -1575);
FORCEPROP 1 LAST VOLTAGE 2.5V
J 0
(3525 -1425);
DISPLAY 0.617021 (3525 -1425);
PAINT SKYBLUE (3525 -1425);
FORCEPROP 1 LAST MATERIAL EMPTY
J 0
(3525 -1475);
DISPLAY 0.617021 (3525 -1475);
PAINT RED (3525 -1475);
FORCEPROP 1 LAST TOLERANCE +10/-35%
J 0
(3525 -1375);
DISPLAY 0.617021 (3525 -1375);
PAINT SKYBLUE (3525 -1375);
FORCEPROP 1 LAST VALUE 330UF
J 0
(3525 -1325);
DISPLAY 0.617021 (3525 -1325);
PAINT SKYBLUE (3525 -1325);
FORCEPROP 1 LAST PACK_TYPE SMLF
J 0
(3525 -1525);
DISPLAY 0.617021 (3525 -1525);
PAINT SKYBLUE (3525 -1525);
FORCEPROP 1 LAST LOCATION PC323
J 0
(3525 -1275);
DISPLAY 0.617021 (3525 -1275);
PAINT AQUA (3525 -1275);
FORCEPROP 1 LASTPIN (3475 -1325) $PN 1
J 0
(3485 -1340);
DISPLAY 0.617021 (3485 -1340);
PAINT MONO (3485 -1340);
FORCEPROP 1 LASTPIN (3475 -1525) $PN 2
J 0
(3485 -1540);
DISPLAY 0.617021 (3485 -1540);
PAINT MONO (3485 -1540);
FORCEPROP 2 LAST CDS_LIB pure_quanta
J 0
(3475 -1425);
DISPLAY INVISIBLE (3475 -1425);
FORCEPROP 1 LAST PATH I64
J 0
(3525 -1275);
DISPLAY 0.978723 (3525 -1275);
DISPLAY INVISIBLE (3525 -1275);
FORCEPROP 1 LAST LOCATION PC323
J 0
(3525 -1225);
DISPLAY 1.021277 (3525 -1225);
PAINT AQUA (3525 -1225);
DISPLAY INVISIBLE (3525 -1225);
FORCEPROP 0 LAST $SEC 1
J 0
(3525 -1225);
DISPLAY 0.680851 (3525 -1225);
PAINT MONO (3525 -1225);
DISPLAY INVISIBLE (3525 -1225);
FORCEPROP 0 LAST CDS_SEC 1
J 0
(3525 -1225);
DISPLAY 1.021277 (3525 -1225);
DISPLAY INVISIBLE (3525 -1225);
FORCEADD UNIVERSAL_GND..1
(3975 -1750);
FORCEPROP 3 LASTPIN (3975 -1700) SIG_NAME GND\g
J 0
(3985 -1690);
DISPLAY 0.659574 (3985 -1690);
PAINT MONO (3985 -1690);
DISPLAY INVISIBLE (3985 -1690);
FORCEPROP 1 LAST HDL_POWER GND
J 1
(4000 -1825);
DISPLAY 0.872340 (4000 -1825);
PAINT GREEN (4000 -1825);
DISPLAY INVISIBLE (4000 -1825);
FORCEPROP 2 LAST CDS_LIB logical_power
J 0
(3975 -1750);
PAINT MONO (3975 -1750);
DISPLAY INVISIBLE (3975 -1750);
FORCEPROP 1 LAST PATH I65
J 0
(4050 -1750);
DISPLAY 0.872340 (4050 -1750);
PAINT AQUA (4050 -1750);
DISPLAY INVISIBLE (4050 -1750);
FORCEADD Q_CAPP..1
(3975 -1425);
FORCEPROP 1 LAST PART_NUMBER CH733LY8802
J 0
(4025 -1575);
DISPLAY 0.617021 (4025 -1575);
PAINT BLUE (4025 -1575);
DISPLAY INVISIBLE (4025 -1575);
FORCEPROP 1 LAST VOLTAGE 2.5V
J 0
(4025 -1425);
DISPLAY 0.617021 (4025 -1425);
PAINT SKYBLUE (4025 -1425);
FORCEPROP 1 LAST TOLERANCE +10/-35%
J 0
(4025 -1375);
DISPLAY 0.617021 (4025 -1375);
PAINT SKYBLUE (4025 -1375);
FORCEPROP 1 LAST VALUE 330UF
J 0
(4025 -1325);
DISPLAY 0.617021 (4025 -1325);
PAINT SKYBLUE (4025 -1325);
FORCEPROP 1 LAST PACK_TYPE SMLF
J 0
(4025 -1525);
DISPLAY 0.617021 (4025 -1525);
PAINT SKYBLUE (4025 -1525);
FORCEPROP 1 LAST MATERIAL EMPTY
J 0
(4025 -1475);
DISPLAY 0.617021 (4025 -1475);
PAINT RED (4025 -1475);
FORCEPROP 1 LAST LOCATION PC326
J 0
(4025 -1275);
DISPLAY 0.617021 (4025 -1275);
PAINT AQUA (4025 -1275);
FORCEPROP 1 LASTPIN (3975 -1325) $PN 1
J 0
(3985 -1340);
DISPLAY 0.617021 (3985 -1340);
PAINT MONO (3985 -1340);
FORCEPROP 1 LASTPIN (3975 -1525) $PN 2
J 0
(3985 -1540);
DISPLAY 0.617021 (3985 -1540);
PAINT MONO (3985 -1540);
FORCEPROP 2 LAST CDS_LIB pure_quanta
J 0
(3975 -1425);
DISPLAY INVISIBLE (3975 -1425);
FORCEPROP 1 LAST PATH I66
J 0
(4025 -1275);
DISPLAY 0.978723 (4025 -1275);
DISPLAY INVISIBLE (4025 -1275);
FORCEPROP 1 LAST LOCATION PC326
J 0
(4025 -1225);
DISPLAY 1.021277 (4025 -1225);
PAINT AQUA (4025 -1225);
DISPLAY INVISIBLE (4025 -1225);
FORCEPROP 0 LAST $SEC 1
J 0
(4025 -1225);
DISPLAY 0.680851 (4025 -1225);
PAINT MONO (4025 -1225);
DISPLAY INVISIBLE (4025 -1225);
FORCEPROP 0 LAST CDS_SEC 1
J 0
(4025 -1225);
DISPLAY 1.021277 (4025 -1225);
DISPLAY INVISIBLE (4025 -1225);
FORCEADD Q_CAPP..1
(3475 -550);
FORCEPROP 1 LAST PART_NUMBER CC7560JMD16
J 0
(3525 -700);
DISPLAY 0.617021 (3525 -700);
PAINT BLUE (3525 -700);
DISPLAY INVISIBLE (3525 -700);
FORCEPROP 1 LAST VOLTAGE 2.5V
J 0
(3525 -550);
DISPLAY 0.617021 (3525 -550);
PAINT SKYBLUE (3525 -550);
FORCEPROP 1 LAST MATERIAL OSCON
J 0
(3525 -600);
DISPLAY 0.617021 (3525 -600);
PAINT SKYBLUE (3525 -600);
FORCEPROP 1 LAST PACK_TYPE THLF
J 0
(3525 -650);
DISPLAY 0.617021 (3525 -650);
PAINT SKYBLUE (3525 -650);
FORCEPROP 1 LAST VALUE 560UF
J 0
(3525 -450);
DISPLAY 0.617021 (3525 -450);
PAINT SKYBLUE (3525 -450);
FORCEPROP 1 LAST TOLERANCE 20%
J 0
(3525 -500);
DISPLAY 0.617021 (3525 -500);
PAINT SKYBLUE (3525 -500);
FORCEPROP 1 LAST LOCATION PC322
J 0
(3525 -400);
DISPLAY 0.617021 (3525 -400);
PAINT AQUA (3525 -400);
FORCEPROP 1 LASTPIN (3475 -450) $PN 1
J 0
(3485 -465);
DISPLAY 0.617021 (3485 -465);
PAINT MONO (3485 -465);
FORCEPROP 1 LASTPIN (3475 -650) $PN 2
J 0
(3485 -665);
DISPLAY 0.617021 (3485 -665);
PAINT MONO (3485 -665);
FORCEPROP 2 LAST CDS_LIB pure_quanta
J 0
(3475 -550);
DISPLAY INVISIBLE (3475 -550);
FORCEPROP 1 LAST PATH I67
J 0
(3525 -400);
DISPLAY 0.978723 (3525 -400);
DISPLAY INVISIBLE (3525 -400);
FORCEPROP 1 LAST LOCATION PC322
J 0
(3525 -350);
DISPLAY 1.021277 (3525 -350);
PAINT AQUA (3525 -350);
DISPLAY INVISIBLE (3525 -350);
FORCEPROP 0 LAST $SEC 1
J 0
(3525 -350);
DISPLAY 0.680851 (3525 -350);
PAINT MONO (3525 -350);
DISPLAY INVISIBLE (3525 -350);
FORCEPROP 0 LAST CDS_SEC 1
J 0
(3525 -350);
DISPLAY 1.021277 (3525 -350);
DISPLAY INVISIBLE (3525 -350);
FORCEADD VCC15..1
(3975 -1100);
FORCEPROP 3 LASTPIN (3975 -1150) SIG_NAME PVCCIN_CPU0\g
J 0
(3985 -1140);
DISPLAY 0.659574 (3985 -1140);
PAINT MONO (3985 -1140);
DISPLAY INVISIBLE (3985 -1140);
FORCEPROP 1 LAST HDL_POWER PVCCIN_CPU0
J 1
(3975 -1050);
DISPLAY 0.617021 (3975 -1050);
PAINT GREEN (3975 -1050);
FORCEPROP 2 LAST CDS_LIB logical_power
J 0
(3975 -1100);
DISPLAY INVISIBLE (3975 -1100);
FORCEPROP 1 LAST PATH I68
J 0
(4025 -1075);
DISPLAY 0.872340 (4025 -1075);
PAINT AQUA (4025 -1075);
DISPLAY INVISIBLE (4025 -1075);
FORCEADD UNIVERSAL_GND..1
(3975 -875);
FORCEPROP 3 LASTPIN (3975 -825) SIG_NAME GND\g
J 0
(3985 -815);
DISPLAY 0.659574 (3985 -815);
PAINT MONO (3985 -815);
DISPLAY INVISIBLE (3985 -815);
FORCEPROP 1 LAST HDL_POWER GND
J 1
(4000 -950);
DISPLAY 0.872340 (4000 -950);
PAINT GREEN (4000 -950);
DISPLAY INVISIBLE (4000 -950);
FORCEPROP 2 LAST CDS_LIB logical_power
J 0
(3975 -875);
PAINT MONO (3975 -875);
DISPLAY INVISIBLE (3975 -875);
FORCEPROP 1 LAST PATH I69
J 0
(4050 -875);
DISPLAY 0.872340 (4050 -875);
PAINT AQUA (4050 -875);
DISPLAY INVISIBLE (4050 -875);
FORCEADD OFFPAGE..1
(-3650 -2225);
FORCEPROP 2 LAST $XR6 272 
J 0
(-4622 -2225);
DISPLAY 0.638298 (-4622 -2225);
PAINT MONO (-4622 -2225);
FORCEPROP 2 LAST $XR5 271 
J 0
(-4502 -2225);
DISPLAY 0.638298 (-4502 -2225);
PAINT MONO (-4502 -2225);
FORCEPROP 2 LAST $XR4 270 
J 0
(-4382 -2225);
DISPLAY 0.638298 (-4382 -2225);
PAINT MONO (-4382 -2225);
FORCEPROP 2 LAST $XR3 269 
J 0
(-4262 -2225);
DISPLAY 0.638298 (-4262 -2225);
PAINT MONO (-4262 -2225);
FORCEPROP 2 LAST $XR2 268 
J 0
(-4142 -2225);
DISPLAY 0.638298 (-4142 -2225);
PAINT MONO (-4142 -2225);
FORCEPROP 2 LAST $XR1 267 
J 0
(-4022 -2225);
DISPLAY 0.638298 (-4022 -2225);
PAINT MONO (-4022 -2225);
FORCEPROP 2 LAST $XR0 266 
J 0
(-3902 -2225);
DISPLAY 0.638298 (-3902 -2225);
PAINT MONO (-3902 -2225);
FORCEPROP 1 LAST COMMENT_BODY TRUE
J 0
(-3525 -2325);
DISPLAY 0.872340 (-3525 -2325);
PAINT GREEN (-3525 -2325);
DISPLAY INVISIBLE (-3525 -2325);
FORCEPROP 1 LAST OFFPAGE TRUE
J 0
(-3325 -2350);
DISPLAY 0.872340 (-3325 -2350);
PAINT GREEN (-3325 -2350);
DISPLAY INVISIBLE (-3325 -2350);
FORCEPROP 2 LAST CDS_LIB standard
J 0
(-3650 -2225);
DISPLAY INVISIBLE (-3650 -2225);
FORCEPROP 2 LAST PATH I7
J 0
(-3900 -2175);
DISPLAY 1.021277 (-3900 -2175);
DISPLAY INVISIBLE (-3900 -2175);
FORCEADD Q_CAPP..1
(3975 -550);
FORCEPROP 1 LAST PART_NUMBER CC7560JMD16
J 0
(4025 -700);
DISPLAY 0.617021 (4025 -700);
PAINT BLUE (4025 -700);
DISPLAY INVISIBLE (4025 -700);
FORCEPROP 1 LAST PACK_TYPE THLF
J 0
(4025 -650);
DISPLAY 0.617021 (4025 -650);
PAINT SKYBLUE (4025 -650);
FORCEPROP 1 LAST VALUE 560UF
J 0
(4025 -450);
DISPLAY 0.617021 (4025 -450);
PAINT SKYBLUE (4025 -450);
FORCEPROP 1 LAST TOLERANCE 20%
J 0
(4025 -500);
DISPLAY 0.617021 (4025 -500);
PAINT SKYBLUE (4025 -500);
FORCEPROP 1 LAST MATERIAL OSCON
J 0
(4025 -600);
DISPLAY 0.617021 (4025 -600);
PAINT SKYBLUE (4025 -600);
FORCEPROP 1 LAST VOLTAGE 2.5V
J 0
(4025 -550);
DISPLAY 0.617021 (4025 -550);
PAINT SKYBLUE (4025 -550);
FORCEPROP 1 LAST LOCATION PC325
J 0
(4025 -400);
DISPLAY 0.617021 (4025 -400);
PAINT AQUA (4025 -400);
FORCEPROP 1 LASTPIN (3975 -450) $PN 1
J 0
(3985 -465);
DISPLAY 0.617021 (3985 -465);
PAINT MONO (3985 -465);
FORCEPROP 1 LASTPIN (3975 -650) $PN 2
J 0
(3985 -665);
DISPLAY 0.617021 (3985 -665);
PAINT MONO (3985 -665);
FORCEPROP 2 LAST CDS_LIB pure_quanta
J 0
(3975 -550);
DISPLAY INVISIBLE (3975 -550);
FORCEPROP 1 LAST PATH I70
J 0
(4025 -400);
DISPLAY 0.978723 (4025 -400);
DISPLAY INVISIBLE (4025 -400);
FORCEPROP 1 LAST LOCATION PC325
J 0
(4025 -350);
DISPLAY 1.021277 (4025 -350);
PAINT AQUA (4025 -350);
DISPLAY INVISIBLE (4025 -350);
FORCEPROP 0 LAST $SEC 1
J 0
(4025 -350);
DISPLAY 0.680851 (4025 -350);
PAINT MONO (4025 -350);
DISPLAY INVISIBLE (4025 -350);
FORCEPROP 0 LAST CDS_SEC 1
J 0
(4025 -350);
DISPLAY 1.021277 (4025 -350);
DISPLAY INVISIBLE (4025 -350);
FORCEADD UNIVERSAL_GND..1
(4025 -2875);
FORCEPROP 3 LASTPIN (4025 -2825) SIG_NAME GND\g
J 0
(4035 -2815);
DISPLAY 0.659574 (4035 -2815);
PAINT MONO (4035 -2815);
DISPLAY INVISIBLE (4035 -2815);
FORCEPROP 1 LAST HDL_POWER GND
J 1
(4050 -2950);
DISPLAY 0.872340 (4050 -2950);
PAINT GREEN (4050 -2950);
DISPLAY INVISIBLE (4050 -2950);
FORCEPROP 2 LAST CDS_LIB logical_power
J 0
(4025 -2875);
PAINT MONO (4025 -2875);
DISPLAY INVISIBLE (4025 -2875);
FORCEPROP 1 LAST PATH I71
J 0
(4100 -2875);
DISPLAY 0.872340 (4100 -2875);
PAINT AQUA (4100 -2875);
DISPLAY INVISIBLE (4100 -2875);
FORCEADD VCC15..1
(4025 -2075);
FORCEPROP 3 LASTPIN (4025 -2125) SIG_NAME PVCCIN_CPU0\g
J 0
(4035 -2115);
DISPLAY 0.659574 (4035 -2115);
PAINT MONO (4035 -2115);
DISPLAY INVISIBLE (4035 -2115);
FORCEPROP 1 LAST HDL_POWER PVCCIN_CPU0
J 1
(4025 -2025);
DISPLAY 0.617021 (4025 -2025);
PAINT GREEN (4025 -2025);
FORCEPROP 2 LAST CDS_LIB logical_power
J 0
(4025 -2075);
DISPLAY INVISIBLE (4025 -2075);
FORCEPROP 1 LAST PATH I72
J 0
(4075 -2050);
DISPLAY 0.872340 (4075 -2050);
PAINT AQUA (4075 -2050);
DISPLAY INVISIBLE (4075 -2050);
FORCEADD Q_RES..1
(100 100);
FORCEPROP 1 LAST PART_NUMBER CS00002JB13
J 0
(-25 150);
DISPLAY 0.617021 (-25 150);
PAINT BLUE (-25 150);
DISPLAY INVISIBLE (-25 150);
FORCEPROP 1 LAST PACK_TYPE 0402LF
J 0
(-25 200);
DISPLAY 0.617021 (-25 200);
PAINT SKYBLUE (-25 200);
FORCEPROP 1 LAST WATTAGE 1/16W
J 2
(350 200);
DISPLAY 0.617021 (350 200);
PAINT SKYBLUE (350 200);
FORCEPROP 1 LAST TOLERANCE 5%
J 0
(300 100);
DISPLAY 0.617021 (300 100);
PAINT SKYBLUE (300 100);
FORCEPROP 1 LAST MATERIAL CHIP
J 0
(375 100);
DISPLAY 0.617021 (375 100);
PAINT SKYBLUE (375 100);
FORCEPROP 1 LAST VALUE 0
J 2
(275 100);
DISPLAY 0.617021 (275 100);
PAINT SKYBLUE (275 100);
FORCEPROP 1 LAST LOCATION PR155
J 0
(-175 100);
DISPLAY 0.617021 (-175 100);
PAINT AQUA (-175 100);
FORCEPROP 1 LASTPIN (0 100) $PN 1
J 0
(12 112);
DISPLAY 0.617021 (12 112);
PAINT MONO (12 112);
FORCEPROP 1 LASTPIN (200 100) $PN 2
J 0
(162 112);
DISPLAY 0.617021 (162 112);
PAINT MONO (162 112);
FORCEPROP 2 LAST CDS_LIB pure_quanta
J 0
(100 100);
DISPLAY INVISIBLE (100 100);
FORCEPROP 1 LAST PATH I73
J 0
(50 250);
DISPLAY 0.978723 (50 250);
PAINT WHITE (50 250);
DISPLAY INVISIBLE (50 250);
FORCEPROP 0 LAST $SEC 1
J 0
(350 250);
DISPLAY 0.680851 (350 250);
PAINT MONO (350 250);
DISPLAY INVISIBLE (350 250);
FORCEPROP 0 LAST CDS_SEC 1
J 0
(350 250);
DISPLAY 1.021277 (350 250);
DISPLAY INVISIBLE (350 250);
FORCEADD UNIVERSAL_GND..1
(350 1175);
FORCEPROP 3 LASTPIN (350 1225) SIG_NAME GND\g
J 0
(360 1235);
DISPLAY 0.659574 (360 1235);
PAINT MONO (360 1235);
DISPLAY INVISIBLE (360 1235);
FORCEPROP 1 LAST HDL_POWER GND
J 1
(375 1100);
DISPLAY 0.872340 (375 1100);
PAINT GREEN (375 1100);
DISPLAY INVISIBLE (375 1100);
FORCEPROP 2 LAST CDS_LIB logical_power
J 0
(350 1175);
PAINT MONO (350 1175);
DISPLAY INVISIBLE (350 1175);
FORCEPROP 1 LAST PATH I74
J 0
(425 1175);
DISPLAY 0.872340 (425 1175);
PAINT AQUA (425 1175);
DISPLAY INVISIBLE (425 1175);
FORCEADD Q_CAP..1
(200 1600);
FORCEPROP 1 LAST PART_NUMBER CH6223MEA01
J 0
(250 1450);
DISPLAY 0.617021 (250 1450);
PAINT BLUE (250 1450);
DISPLAY INVISIBLE (250 1450);
FORCEPROP 1 LAST TOLERANCE 20%
J 0
(250 1600);
DISPLAY 0.617021 (250 1600);
PAINT SKYBLUE (250 1600);
FORCEPROP 1 LAST PACK_TYPE C0805
J 0
(250 1500);
DISPLAY 0.617021 (250 1500);
PAINT SKYBLUE (250 1500);
FORCEPROP 1 LAST VALUE 22UF
J 0
(250 1700);
DISPLAY 0.617021 (250 1700);
PAINT SKYBLUE (250 1700);
FORCEPROP 1 LAST MATERIAL X6S
J 0
(250 1550);
DISPLAY 0.617021 (250 1550);
PAINT SKYBLUE (250 1550);
FORCEPROP 1 LAST VOLTAGE 16V
J 0
(250 1650);
DISPLAY 0.617021 (250 1650);
PAINT SKYBLUE (250 1650);
FORCEPROP 1 LAST LOCATION PC307_P0_1
J 0
(250 1750);
DISPLAY 0.617021 (250 1750);
PAINT AQUA (250 1750);
FORCEPROP 1 LASTPIN (200 1700) $PN 1
J 0
(210 1680);
DISPLAY 0.617021 (210 1680);
PAINT MONO (210 1680);
FORCEPROP 1 LASTPIN (200 1500) $PN 2
J 0
(210 1480);
DISPLAY 0.617021 (210 1480);
PAINT MONO (210 1480);
FORCEPROP 2 LAST CDS_LIB pure_quanta
J 0
(200 1600);
DISPLAY INVISIBLE (200 1600);
FORCEPROP 1 LAST PATH I75
J 0
(250 1750);
DISPLAY 0.978723 (250 1750);
PAINT WHITE (250 1750);
DISPLAY INVISIBLE (250 1750);
FORCEPROP 1 LAST LOCATION PC307_P0_1
J 0
(250 1800);
DISPLAY 1.021277 (250 1800);
PAINT AQUA (250 1800);
DISPLAY INVISIBLE (250 1800);
FORCEPROP 0 LAST $SEC 1
J 0
(250 1800);
DISPLAY 0.680851 (250 1800);
PAINT MONO (250 1800);
DISPLAY INVISIBLE (250 1800);
FORCEPROP 0 LAST CDS_SEC 1
J 0
(250 1800);
DISPLAY 1.021277 (250 1800);
DISPLAY INVISIBLE (250 1800);
FORCEADD OFFPAGE..3
(1125 450);
FORCEPROP 2 LAST $XR0 267 
J 0
(1339 450);
DISPLAY 0.638298 (1339 450);
PAINT MONO (1339 450);
FORCEPROP 1 LAST COMMENT_BODY TRUE
J 0
(1075 350);
DISPLAY 0.872340 (1075 350);
PAINT GREEN (1075 350);
DISPLAY INVISIBLE (1075 350);
FORCEPROP 1 LAST OFFPAGE TRUE
J 0
(1450 325);
DISPLAY 0.872340 (1450 325);
PAINT GREEN (1450 325);
DISPLAY INVISIBLE (1450 325);
FORCEPROP 2 LAST CDS_LIB standard
J 0
(1125 450);
DISPLAY INVISIBLE (1125 450);
FORCEPROP 2 LAST PATH I76
J 0
(1350 500);
DISPLAY 1.021277 (1350 500);
DISPLAY INVISIBLE (1350 500);
FORCEADD GND..1
(1450 1575);
FORCEPROP 3 LASTPIN (1450 1625) SIG_NAME GND\g
J 0
(1460 1635);
DISPLAY 0.659574 (1460 1635);
PAINT MONO (1460 1635);
DISPLAY INVISIBLE (1460 1635);
FORCEPROP 1 LAST HDL_POWER GND
J 0
(1450 1725);
DISPLAY 0.872340 (1450 1725);
PAINT GREEN (1450 1725);
DISPLAY INVISIBLE (1450 1725);
FORCEPROP 1 LAST SIZE 1B
J 0
(1525 1525);
DISPLAY 0.872340 (1525 1525);
PAINT AQUA (1525 1525);
DISPLAY INVISIBLE (1525 1525);
FORCEPROP 2 LAST CDS_LIB logical_power
J 0
(1450 1575);
DISPLAY INVISIBLE (1450 1575);
FORCEPROP 1 LAST PATH I77
J 0
(1525 1575);
DISPLAY 0.872340 (1525 1575);
PAINT AQUA (1525 1575);
DISPLAY INVISIBLE (1525 1575);
FORCEADD VCC15..1
(350 1975);
FORCEPROP 3 LASTPIN (350 1925) SIG_NAME SW_P12V_PVCCIN_CPU0_FLT\g
J 0
(360 1935);
DISPLAY 0.659574 (360 1935);
PAINT MONO (360 1935);
DISPLAY INVISIBLE (360 1935);
FORCEPROP 1 LAST HDL_POWER SW_P12V_PVCCIN_CPU0_FLT
J 1
(400 2025);
DISPLAY 0.617021 (400 2025);
PAINT GREEN (400 2025);
FORCEPROP 2 LAST CDS_LIB logical_power
J 0
(350 1975);
DISPLAY INVISIBLE (350 1975);
FORCEPROP 1 LAST PATH I78
J 0
(400 2000);
DISPLAY 0.872340 (400 2000);
PAINT AQUA (400 2000);
DISPLAY INVISIBLE (400 2000);
FORCEADD VCC15..1
(1450 2200);
FORCEPROP 3 LASTPIN (1450 2150) SIG_NAME P12V_AUX\g
J 0
(1460 2160);
DISPLAY 0.659574 (1460 2160);
PAINT MONO (1460 2160);
DISPLAY INVISIBLE (1460 2160);
FORCEPROP 1 LAST HDL_POWER P12V_AUX
J 1
(1450 2250);
DISPLAY 0.617021 (1450 2250);
PAINT GREEN (1450 2250);
FORCEPROP 2 LAST CDS_LIB logical_power
J 0
(1450 2200);
DISPLAY INVISIBLE (1450 2200);
FORCEPROP 1 LAST PATH I79
J 0
(1500 2225);
DISPLAY 0.872340 (1500 2225);
PAINT AQUA (1500 2225);
DISPLAY INVISIBLE (1500 2225);
FORCEADD OFFPAGE..5
(-3650 -2125);
FORCEPROP 2 LAST $XR0 266 
J 0
(-3905 -2125);
DISPLAY 0.638298 (-3905 -2125);
PAINT MONO (-3905 -2125);
FORCEPROP 1 LAST COMMENT_BODY TRUE
J 0
(-3550 -2200);
DISPLAY 0.872340 (-3550 -2200);
PAINT GREEN (-3550 -2200);
DISPLAY INVISIBLE (-3550 -2200);
FORCEPROP 1 LAST OFFPAGE TRUE
J 0
(-3325 -2250);
DISPLAY 0.872340 (-3325 -2250);
PAINT GREEN (-3325 -2250);
DISPLAY INVISIBLE (-3325 -2250);
FORCEPROP 2 LAST CDS_LIB standard
J 0
(-3650 -2125);
DISPLAY INVISIBLE (-3650 -2125);
FORCEPROP 2 LAST PATH I8
J 0
(-3900 -2075);
DISPLAY 1.021277 (-3900 -2075);
DISPLAY INVISIBLE (-3900 -2075);
FORCEADD Q_CAP..1
R 2
(1450 1825);
FORCEPROP 1 LAST PART_NUMBER CH4106K1B01
J 2
(1400 1675);
DISPLAY 0.787234 (1400 1675);
DISPLAY INVISIBLE (1400 1675);
FORCEPROP 1 LAST PACK_TYPE C0402
J 2
(1400 1625);
DISPLAY 0.787234 (1400 1625);
FORCEPROP 1 LAST VALUE 100NF
J 2
(1400 1875);
DISPLAY 0.787234 (1400 1875);
FORCEPROP 1 LAST MATERIAL X7R
J 2
(1400 1725);
DISPLAY 0.787234 (1400 1725);
FORCEPROP 1 LAST TOLERANCE 10%
J 2
(1400 1775);
DISPLAY 0.787234 (1400 1775);
FORCEPROP 1 LAST VOLTAGE 50V
J 2
(1400 1825);
DISPLAY 0.787234 (1400 1825);
FORCEPROP 1 LAST LOCATION PC1652
J 2
(1400 1925);
DISPLAY 0.787234 (1400 1925);
FORCEPROP 1 LASTPIN (1450 1925) $PN 1
J 2
(1440 1905);
DISPLAY 0.787234 (1440 1905);
PAINT MONO (1440 1905);
FORCEPROP 1 LASTPIN (1450 1725) $PN 2
J 2
(1440 1705);
DISPLAY 0.787234 (1440 1705);
PAINT MONO (1440 1705);
FORCEPROP 2 LAST CDS_LIB pure_quanta
J 2
(1450 1825);
DISPLAY INVISIBLE (1450 1825);
FORCEPROP 1 LAST PATH I80
J 2
(1400 1975);
DISPLAY 0.978723 (1400 1975);
PAINT WHITE (1400 1975);
DISPLAY INVISIBLE (1400 1975);
FORCEPROP 0 LAST $SEC 1
J 2
(1400 1975);
DISPLAY 0.680851 (1400 1975);
PAINT MONO (1400 1975);
DISPLAY INVISIBLE (1400 1975);
FORCEPROP 0 LAST CDS_SEC 1
J 2
(1400 1975);
DISPLAY 1.021277 (1400 1975);
DISPLAY INVISIBLE (1400 1975);
FORCEADD Q_RES..1
(1875 1900);
FORCEPROP 1 LAST PART_NUMBER TMP_QCS+0308BR00
J 0
(1700 1825);
DISPLAY 0.638298 (1700 1825);
DISPLAY INVISIBLE (1700 1825);
FORCEPROP 1 LAST VALUE 0.03
J 2
(2100 1900);
DISPLAY 0.638298 (2100 1900);
FORCEPROP 1 LAST TOLERANCE 0.1%
J 0
(2125 1900);
DISPLAY 0.638298 (2125 1900);
FORCEPROP 1 LAST PACK_TYPE 2512LF
J 0
(1700 1750);
DISPLAY 0.638298 (1700 1750);
FORCEPROP 1 LAST MATERIAL EMPTY
J 0
(2025 1750);
DISPLAY 0.638298 (2025 1750);
PAINT RED (2025 1750);
FORCEPROP 1 LAST WATTAGE 1W
J 2
(1975 1750);
DISPLAY 0.638298 (1975 1750);
FORCEPROP 1 LAST LOCATION PR2554
J 0
(1625 1900);
DISPLAY 0.638298 (1625 1900);
FORCEPROP 1 LASTPIN (1775 1900) $PN 1
J 0
(1787 1912);
DISPLAY 0.787234 (1787 1912);
PAINT MONO (1787 1912);
FORCEPROP 1 LASTPIN (1975 1900) $PN 2
J 0
(1937 1912);
DISPLAY 0.787234 (1937 1912);
PAINT MONO (1937 1912);
FORCEPROP 2 LAST CDS_LIB pure_quanta
J 0
(1875 1900);
DISPLAY INVISIBLE (1875 1900);
FORCEPROP 1 LAST PATH I81
J 0
(1825 2050);
DISPLAY 0.978723 (1825 2050);
PAINT WHITE (1825 2050);
DISPLAY INVISIBLE (1825 2050);
FORCEPROP 0 LAST $SEC 1
J 0
(2125 1950);
DISPLAY 0.680851 (2125 1950);
PAINT MONO (2125 1950);
DISPLAY INVISIBLE (2125 1950);
FORCEPROP 0 LAST CDS_SEC 1
J 0
(2125 1950);
DISPLAY 1.021277 (2125 1950);
DISPLAY INVISIBLE (2125 1950);
FORCEADD Q_INDUCTOR..1
(1875 2050);
FORCEPROP 1 LAST PART_NUMBER CVA50^0EZ01
J 0
(1750 2160);
DISPLAY 0.617021 (1750 2160);
PAINT BLUE (1750 2160);
DISPLAY INVISIBLE (1750 2160);
FORCEPROP 2 LAST VALUE 50NH/148A
J 0
(1750 2225);
DISPLAY 0.617021 (1750 2225);
PAINT SKYBLUE (1750 2225);
FORCEPROP 2 LAST PACK_TYPE SMLF
J 0
(1750 2275);
DISPLAY 0.617021 (1750 2275);
PAINT SKYBLUE (1750 2275);
FORCEPROP 1 LAST MATERIAL IND
J 0
(1750 2105);
DISPLAY 0.617021 (1750 2105);
PAINT SKYBLUE (1750 2105);
FORCEPROP 1 LAST LOCATION PL15
J 0
(1625 2035);
DISPLAY 0.617021 (1625 2035);
PAINT AQUA (1625 2035);
FORCEPROP 2 LASTPIN (1775 2025) $PN 1
J 2
(1765 2035);
DISPLAY 0.617021 (1765 2035);
FORCEPROP 2 LASTPIN (1975 2025) $PN 2
J 0
(1985 2035);
DISPLAY 0.617021 (1985 2035);
FORCEPROP 2 LAST CDS_LIB pure_quanta
J 0
(1875 2050);
PAINT MONO (1875 2050);
DISPLAY INVISIBLE (1875 2050);
FORCEPROP 1 LAST NEEDS_NO_SIZE TRUE
J 0
(1875 2050);
DISPLAY 0.468085 (1875 2050);
PAINT GREEN (1875 2050);
DISPLAY INVISIBLE (1875 2050);
FORCEPROP 1 LAST PATH I82
J 0
(1950 2105);
DISPLAY 0.723404 (1950 2105);
PAINT GREEN (1950 2105);
DISPLAY INVISIBLE (1950 2105);
FORCEPROP 2 LAST $SEC 1
J 0
(1750 2325);
DISPLAY 0.680851 (1750 2325);
PAINT MONO (1750 2325);
DISPLAY INVISIBLE (1750 2325);
FORCEPROP 0 LAST CDS_SEC 1
J 0
(1850 2150);
DISPLAY 1.021277 (1850 2150);
DISPLAY INVISIBLE (1850 2150);
FORCEADD Q_CAP..1
(1975 500);
FORCEPROP 1 LAST PART_NUMBER CH4106K1B01
J 0
(2025 325);
DISPLAY 0.617021 (2025 325);
PAINT BLUE (2025 325);
DISPLAY INVISIBLE (2025 325);
FORCEPROP 1 LAST VOLTAGE 50V
J 0
(2025 525);
DISPLAY 0.617021 (2025 525);
PAINT SKYBLUE (2025 525);
FORCEPROP 1 LAST TOLERANCE 10%
J 0
(2025 475);
DISPLAY 0.617021 (2025 475);
PAINT SKYBLUE (2025 475);
FORCEPROP 1 LAST MATERIAL X7R
J 0
(2025 425);
DISPLAY 0.617021 (2025 425);
PAINT SKYBLUE (2025 425);
FORCEPROP 1 LAST PACK_TYPE C0402
J 0
(2025 375);
DISPLAY 0.617021 (2025 375);
PAINT SKYBLUE (2025 375);
FORCEPROP 1 LAST VALUE 100NF
J 0
(2025 575);
DISPLAY 0.617021 (2025 575);
PAINT SKYBLUE (2025 575);
FORCEPROP 1 LAST LOCATION PC308_P0_1
J 0
(2025 625);
DISPLAY 0.617021 (2025 625);
PAINT AQUA (2025 625);
FORCEPROP 1 LASTPIN (1975 600) $PN 1
J 0
(1985 580);
DISPLAY 0.617021 (1985 580);
PAINT MONO (1985 580);
FORCEPROP 1 LASTPIN (1975 400) $PN 2
J 0
(1985 380);
DISPLAY 0.617021 (1985 380);
PAINT MONO (1985 380);
FORCEPROP 2 LAST CDS_LIB pure_quanta
J 0
(1975 500);
DISPLAY INVISIBLE (1975 500);
FORCEPROP 1 LAST PATH I83
J 0
(2025 650);
DISPLAY 0.978723 (2025 650);
PAINT WHITE (2025 650);
DISPLAY INVISIBLE (2025 650);
FORCEPROP 1 LAST LOCATION PC308_P0_1
J 0
(2025 675);
DISPLAY 1.021277 (2025 675);
PAINT AQUA (2025 675);
DISPLAY INVISIBLE (2025 675);
FORCEPROP 0 LAST $SEC 1
J 0
(2025 675);
DISPLAY 0.680851 (2025 675);
PAINT MONO (2025 675);
DISPLAY INVISIBLE (2025 675);
FORCEPROP 0 LAST CDS_SEC 1
J 0
(2025 675);
DISPLAY 1.021277 (2025 675);
DISPLAY INVISIBLE (2025 675);
FORCEADD Q_CAP..1
(2375 500);
FORCEPROP 1 LAST PART_NUMBER CH5103KEB01
J 0
(2425 325);
DISPLAY 0.617021 (2425 325);
PAINT BLUE (2425 325);
DISPLAY INVISIBLE (2425 325);
FORCEPROP 1 LAST MATERIAL X6S
J 0
(2425 425);
DISPLAY 0.617021 (2425 425);
PAINT SKYBLUE (2425 425);
FORCEPROP 1 LAST TOLERANCE 10%
J 0
(2425 475);
DISPLAY 0.617021 (2425 475);
PAINT SKYBLUE (2425 475);
FORCEPROP 1 LAST VALUE 1UF
J 0
(2425 575);
DISPLAY 0.617021 (2425 575);
PAINT SKYBLUE (2425 575);
FORCEPROP 1 LAST VOLTAGE 16V
J 0
(2425 525);
DISPLAY 0.617021 (2425 525);
PAINT SKYBLUE (2425 525);
FORCEPROP 1 LAST PACK_TYPE C0402
J 0
(2425 375);
DISPLAY 0.617021 (2425 375);
PAINT SKYBLUE (2425 375);
FORCEPROP 1 LAST LOCATION PC310_P0_1
J 0
(2425 625);
DISPLAY 0.617021 (2425 625);
PAINT AQUA (2425 625);
FORCEPROP 1 LASTPIN (2375 600) $PN 1
J 0
(2385 580);
DISPLAY 0.617021 (2385 580);
PAINT MONO (2385 580);
FORCEPROP 1 LASTPIN (2375 400) $PN 2
J 0
(2385 380);
DISPLAY 0.617021 (2385 380);
PAINT MONO (2385 380);
FORCEPROP 2 LAST CDS_LIB pure_quanta
J 0
(2375 500);
DISPLAY INVISIBLE (2375 500);
FORCEPROP 1 LAST PATH I84
J 0
(2425 650);
DISPLAY 0.978723 (2425 650);
PAINT WHITE (2425 650);
DISPLAY INVISIBLE (2425 650);
FORCEPROP 1 LAST LOCATION PC310_P0_1
J 0
(2425 675);
DISPLAY 1.021277 (2425 675);
PAINT AQUA (2425 675);
DISPLAY INVISIBLE (2425 675);
FORCEPROP 0 LAST $SEC 1
J 0
(2425 675);
DISPLAY 0.680851 (2425 675);
PAINT MONO (2425 675);
DISPLAY INVISIBLE (2425 675);
FORCEPROP 0 LAST CDS_SEC 1
J 0
(2425 675);
DISPLAY 1.021277 (2425 675);
DISPLAY INVISIBLE (2425 675);
FORCEADD Q_CAP..1
(2800 500);
FORCEPROP 1 LAST PART_NUMBER CH622KMEA03
J 0
(2850 325);
DISPLAY 0.617021 (2850 325);
PAINT BLUE (2850 325);
DISPLAY INVISIBLE (2850 325);
FORCEPROP 1 LAST TOLERANCE 20%
J 0
(2850 475);
DISPLAY 0.617021 (2850 475);
PAINT SKYBLUE (2850 475);
FORCEPROP 1 LAST PACK_TYPE C0805
J 0
(2850 375);
DISPLAY 0.617021 (2850 375);
PAINT SKYBLUE (2850 375);
FORCEPROP 1 LAST MATERIAL X6S
J 0
(2850 425);
DISPLAY 0.617021 (2850 425);
PAINT SKYBLUE (2850 425);
FORCEPROP 1 LAST VALUE 22UF
J 0
(2850 575);
DISPLAY 0.617021 (2850 575);
PAINT SKYBLUE (2850 575);
FORCEPROP 1 LAST VOLTAGE 4V
J 0
(2850 525);
DISPLAY 0.617021 (2850 525);
PAINT SKYBLUE (2850 525);
FORCEPROP 1 LAST LOCATION PC312_P0_1
J 0
(2850 625);
DISPLAY 0.617021 (2850 625);
PAINT AQUA (2850 625);
FORCEPROP 1 LASTPIN (2800 600) $PN 1
J 0
(2810 580);
DISPLAY 0.617021 (2810 580);
PAINT MONO (2810 580);
FORCEPROP 1 LASTPIN (2800 400) $PN 2
J 0
(2810 380);
DISPLAY 0.617021 (2810 380);
PAINT MONO (2810 380);
FORCEPROP 2 LAST CDS_LIB pure_quanta
J 0
(2800 500);
DISPLAY INVISIBLE (2800 500);
FORCEPROP 1 LAST PATH I85
J 0
(2850 650);
DISPLAY 0.978723 (2850 650);
PAINT WHITE (2850 650);
DISPLAY INVISIBLE (2850 650);
FORCEPROP 1 LAST LOCATION PC312_P0_1
J 0
(2850 675);
DISPLAY 1.021277 (2850 675);
PAINT AQUA (2850 675);
DISPLAY INVISIBLE (2850 675);
FORCEPROP 0 LAST $SEC 1
J 0
(2850 675);
DISPLAY 0.680851 (2850 675);
PAINT MONO (2850 675);
DISPLAY INVISIBLE (2850 675);
FORCEPROP 0 LAST CDS_SEC 1
J 0
(2850 675);
DISPLAY 1.021277 (2850 675);
DISPLAY INVISIBLE (2850 675);
FORCEADD Q_CAP..1
(3225 500);
FORCEPROP 1 LAST PART_NUMBER CH622KMEA03
J 0
(3275 325);
DISPLAY 0.617021 (3275 325);
PAINT BLUE (3275 325);
DISPLAY INVISIBLE (3275 325);
FORCEPROP 1 LAST VOLTAGE 4V
J 0
(3275 525);
DISPLAY 0.617021 (3275 525);
PAINT SKYBLUE (3275 525);
FORCEPROP 1 LAST VALUE 22UF
J 0
(3275 575);
DISPLAY 0.617021 (3275 575);
PAINT SKYBLUE (3275 575);
FORCEPROP 1 LAST TOLERANCE 20%
J 0
(3275 475);
DISPLAY 0.617021 (3275 475);
PAINT SKYBLUE (3275 475);
FORCEPROP 1 LAST PACK_TYPE C0805
J 0
(3275 375);
DISPLAY 0.617021 (3275 375);
PAINT SKYBLUE (3275 375);
FORCEPROP 1 LAST MATERIAL X6S
J 0
(3275 425);
DISPLAY 0.617021 (3275 425);
PAINT SKYBLUE (3275 425);
FORCEPROP 1 LAST LOCATION PC314_P0_1
J 0
(3275 625);
DISPLAY 0.617021 (3275 625);
PAINT AQUA (3275 625);
FORCEPROP 1 LASTPIN (3225 600) $PN 1
J 0
(3235 580);
DISPLAY 0.617021 (3235 580);
PAINT MONO (3235 580);
FORCEPROP 1 LASTPIN (3225 400) $PN 2
J 0
(3235 380);
DISPLAY 0.617021 (3235 380);
PAINT MONO (3235 380);
FORCEPROP 2 LAST CDS_LIB pure_quanta
J 0
(3225 500);
DISPLAY INVISIBLE (3225 500);
FORCEPROP 1 LAST PATH I86
J 0
(3275 650);
DISPLAY 0.978723 (3275 650);
PAINT WHITE (3275 650);
DISPLAY INVISIBLE (3275 650);
FORCEPROP 1 LAST LOCATION PC314_P0_1
J 0
(3275 675);
DISPLAY 1.021277 (3275 675);
PAINT AQUA (3275 675);
DISPLAY INVISIBLE (3275 675);
FORCEPROP 0 LAST $SEC 1
J 0
(3275 675);
DISPLAY 0.680851 (3275 675);
PAINT MONO (3275 675);
DISPLAY INVISIBLE (3275 675);
FORCEPROP 0 LAST CDS_SEC 1
J 0
(3275 675);
DISPLAY 1.021277 (3275 675);
DISPLAY INVISIBLE (3275 675);
FORCEADD UNIVERSAL_GND..1
(3525 125);
FORCEPROP 3 LASTPIN (3525 175) SIG_NAME GND\g
J 0
(3535 185);
DISPLAY 0.659574 (3535 185);
PAINT MONO (3535 185);
DISPLAY INVISIBLE (3535 185);
FORCEPROP 1 LAST HDL_POWER GND
J 1
(3550 50);
DISPLAY 0.872340 (3550 50);
PAINT GREEN (3550 50);
DISPLAY INVISIBLE (3550 50);
FORCEPROP 2 LAST CDS_LIB logical_power
J 0
(3525 125);
PAINT MONO (3525 125);
DISPLAY INVISIBLE (3525 125);
FORCEPROP 1 LAST PATH I87
J 0
(3600 125);
DISPLAY 0.872340 (3600 125);
PAINT AQUA (3600 125);
DISPLAY INVISIBLE (3600 125);
FORCEADD VCC15..1
(3975 -225);
FORCEPROP 3 LASTPIN (3975 -275) SIG_NAME PVCCIN_CPU0\g
J 0
(3985 -265);
DISPLAY 0.659574 (3985 -265);
PAINT MONO (3985 -265);
DISPLAY INVISIBLE (3985 -265);
FORCEPROP 1 LAST HDL_POWER PVCCIN_CPU0
J 1
(3975 -175);
DISPLAY 0.617021 (3975 -175);
PAINT GREEN (3975 -175);
FORCEPROP 2 LAST CDS_LIB logical_power
J 0
(3975 -225);
DISPLAY INVISIBLE (3975 -225);
FORCEPROP 1 LAST PATH I88
J 0
(4025 -200);
DISPLAY 0.872340 (4025 -200);
PAINT AQUA (4025 -200);
DISPLAY INVISIBLE (4025 -200);
FORCEADD VCC15..1
(3525 900);
FORCEPROP 3 LASTPIN (3525 850) SIG_NAME PVCCIN_CPU0\g
J 0
(3535 860);
DISPLAY 0.659574 (3535 860);
PAINT MONO (3535 860);
DISPLAY INVISIBLE (3535 860);
FORCEPROP 1 LAST HDL_POWER PVCCIN_CPU0
J 1
(3525 950);
DISPLAY 0.617021 (3525 950);
PAINT GREEN (3525 950);
FORCEPROP 2 LAST CDS_LIB logical_power
J 0
(3525 900);
DISPLAY INVISIBLE (3525 900);
FORCEPROP 1 LAST PATH I89
J 0
(3575 925);
DISPLAY 0.872340 (3575 925);
PAINT AQUA (3575 925);
DISPLAY INVISIBLE (3575 925);
FORCEADD Q_CAP..1
(-3800 -1625);
FORCEPROP 1 LAST PART_NUMBER CH5222KEB01
J 0
(-3750 -1800);
DISPLAY 0.617021 (-3750 -1800);
PAINT BLUE (-3750 -1800);
DISPLAY INVISIBLE (-3750 -1800);
FORCEPROP 1 LAST PACK_TYPE C0402
J 0
(-3750 -1750);
DISPLAY 0.617021 (-3750 -1750);
PAINT SKYBLUE (-3750 -1750);
FORCEPROP 1 LAST VOLTAGE 10V
J 0
(-3750 -1600);
DISPLAY 0.617021 (-3750 -1600);
PAINT SKYBLUE (-3750 -1600);
FORCEPROP 1 LAST VALUE 2.2UF
J 0
(-3750 -1550);
DISPLAY 0.617021 (-3750 -1550);
PAINT SKYBLUE (-3750 -1550);
FORCEPROP 1 LAST TOLERANCE 10%
J 0
(-3750 -1650);
DISPLAY 0.617021 (-3750 -1650);
PAINT SKYBLUE (-3750 -1650);
FORCEPROP 1 LAST MATERIAL X6S
J 0
(-3750 -1700);
DISPLAY 0.617021 (-3750 -1700);
PAINT SKYBLUE (-3750 -1700);
FORCEPROP 1 LAST LOCATION PC292
J 0
(-3750 -1500);
DISPLAY 0.617021 (-3750 -1500);
PAINT AQUA (-3750 -1500);
FORCEPROP 1 LASTPIN (-3800 -1525) $PN 1
J 0
(-3790 -1545);
DISPLAY 0.617021 (-3790 -1545);
PAINT MONO (-3790 -1545);
FORCEPROP 1 LASTPIN (-3800 -1725) $PN 2
J 0
(-3790 -1745);
DISPLAY 0.617021 (-3790 -1745);
PAINT MONO (-3790 -1745);
FORCEPROP 2 LAST CDS_LIB pure_quanta
J 0
(-3800 -1625);
DISPLAY INVISIBLE (-3800 -1625);
FORCEPROP 1 LAST PATH I9
J 0
(-3750 -1475);
DISPLAY 0.978723 (-3750 -1475);
PAINT WHITE (-3750 -1475);
DISPLAY INVISIBLE (-3750 -1475);
FORCEPROP 1 LAST LOCATION PC292
J 0
(-3750 -1450);
DISPLAY 1.021277 (-3750 -1450);
PAINT AQUA (-3750 -1450);
DISPLAY INVISIBLE (-3750 -1450);
FORCEPROP 0 LAST $SEC 1
J 0
(-3750 -1450);
DISPLAY 0.680851 (-3750 -1450);
PAINT MONO (-3750 -1450);
DISPLAY INVISIBLE (-3750 -1450);
FORCEPROP 0 LAST CDS_SEC 1
J 0
(-3750 -1450);
DISPLAY 1.021277 (-3750 -1450);
DISPLAY INVISIBLE (-3750 -1450);
FORCEADD UNIVERSAL_GND..1
(3950 1500);
FORCEPROP 3 LASTPIN (3950 1550) SIG_NAME GND\g
J 0
(3960 1560);
DISPLAY 0.659574 (3960 1560);
PAINT MONO (3960 1560);
DISPLAY INVISIBLE (3960 1560);
FORCEPROP 1 LAST HDL_POWER GND
J 1
(3975 1425);
DISPLAY 0.872340 (3975 1425);
PAINT GREEN (3975 1425);
DISPLAY INVISIBLE (3975 1425);
FORCEPROP 2 LAST CDS_LIB logical_power
J 0
(3950 1500);
PAINT MONO (3950 1500);
DISPLAY INVISIBLE (3950 1500);
FORCEPROP 1 LAST PATH I90
J 0
(4025 1500);
DISPLAY 0.872340 (4025 1500);
PAINT AQUA (4025 1500);
DISPLAY INVISIBLE (4025 1500);
FORCEADD Q_CAPP..1
(2350 1825);
FORCEPROP 1 LAST PART_NUMBER CC72703MD38
J 0
(2400 1650);
DISPLAY 0.617021 (2400 1650);
PAINT BLUE (2400 1650);
DISPLAY INVISIBLE (2400 1650);
FORCEPROP 1 LAST VOLTAGE 16V
J 0
(2400 1800);
DISPLAY 0.617021 (2400 1800);
PAINT SKYBLUE (2400 1800);
FORCEPROP 1 LAST PACK_TYPE THLF
J 0
(2400 1700);
DISPLAY 0.617021 (2400 1700);
PAINT SKYBLUE (2400 1700);
FORCEPROP 1 LAST VALUE 270UF
J 0
(2400 1900);
DISPLAY 0.617021 (2400 1900);
PAINT SKYBLUE (2400 1900);
FORCEPROP 1 LAST TOLERANCE 20%
J 0
(2400 1850);
DISPLAY 0.617021 (2400 1850);
PAINT SKYBLUE (2400 1850);
FORCEPROP 1 LAST MATERIAL OSCON
J 0
(2400 1750);
DISPLAY 0.617021 (2400 1750);
PAINT SKYBLUE (2400 1750);
FORCEPROP 1 LAST LOCATION PC315
J 0
(2400 1950);
DISPLAY 0.617021 (2400 1950);
PAINT AQUA (2400 1950);
FORCEPROP 1 LASTPIN (2350 1925) $PN 1
J 0
(2360 1910);
DISPLAY 0.617021 (2360 1910);
PAINT MONO (2360 1910);
FORCEPROP 1 LASTPIN (2350 1725) $PN 2
J 0
(2360 1710);
DISPLAY 0.617021 (2360 1710);
PAINT MONO (2360 1710);
FORCEPROP 2 LAST CDS_LIB pure_quanta
J 0
(2350 1825);
DISPLAY INVISIBLE (2350 1825);
FORCEPROP 1 LAST PATH I91
J 0
(2400 1975);
DISPLAY 0.978723 (2400 1975);
DISPLAY INVISIBLE (2400 1975);
FORCEPROP 1 LAST LOCATION PC315
J 0
(2400 2000);
DISPLAY 1.021277 (2400 2000);
PAINT AQUA (2400 2000);
DISPLAY INVISIBLE (2400 2000);
FORCEPROP 0 LAST $SEC 1
J 0
(2400 2000);
DISPLAY 0.680851 (2400 2000);
PAINT MONO (2400 2000);
DISPLAY INVISIBLE (2400 2000);
FORCEPROP 0 LAST CDS_SEC 1
J 0
(2400 2000);
DISPLAY 1.021277 (2400 2000);
DISPLAY INVISIBLE (2400 2000);
FORCEADD Q_CAPP..1
(2750 1825);
FORCEPROP 1 LAST PART_NUMBER CC72703MD38
J 0
(2800 1650);
DISPLAY 0.617021 (2800 1650);
PAINT BLUE (2800 1650);
DISPLAY INVISIBLE (2800 1650);
FORCEPROP 1 LAST TOLERANCE 20%
J 0
(2800 1850);
DISPLAY 0.617021 (2800 1850);
PAINT SKYBLUE (2800 1850);
FORCEPROP 1 LAST VALUE 270UF
J 0
(2800 1900);
DISPLAY 0.617021 (2800 1900);
PAINT SKYBLUE (2800 1900);
FORCEPROP 1 LAST MATERIAL OSCON
J 0
(2800 1750);
DISPLAY 0.617021 (2800 1750);
PAINT SKYBLUE (2800 1750);
FORCEPROP 1 LAST VOLTAGE 16V
J 0
(2800 1800);
DISPLAY 0.617021 (2800 1800);
PAINT SKYBLUE (2800 1800);
FORCEPROP 1 LAST PACK_TYPE THLF
J 0
(2800 1700);
DISPLAY 0.617021 (2800 1700);
PAINT SKYBLUE (2800 1700);
FORCEPROP 1 LAST LOCATION PC318
J 0
(2800 1950);
DISPLAY 0.617021 (2800 1950);
PAINT AQUA (2800 1950);
FORCEPROP 1 LASTPIN (2750 1925) $PN 1
J 0
(2760 1910);
DISPLAY 0.617021 (2760 1910);
PAINT MONO (2760 1910);
FORCEPROP 1 LASTPIN (2750 1725) $PN 2
J 0
(2760 1710);
DISPLAY 0.617021 (2760 1710);
PAINT MONO (2760 1710);
FORCEPROP 2 LAST CDS_LIB pure_quanta
J 0
(2750 1825);
DISPLAY INVISIBLE (2750 1825);
FORCEPROP 1 LAST PATH I92
J 0
(2800 1975);
DISPLAY 0.978723 (2800 1975);
DISPLAY INVISIBLE (2800 1975);
FORCEPROP 1 LAST LOCATION PC318
J 0
(2800 2000);
DISPLAY 1.021277 (2800 2000);
PAINT AQUA (2800 2000);
DISPLAY INVISIBLE (2800 2000);
FORCEPROP 0 LAST $SEC 1
J 0
(2800 2000);
DISPLAY 0.680851 (2800 2000);
PAINT MONO (2800 2000);
DISPLAY INVISIBLE (2800 2000);
FORCEPROP 0 LAST CDS_SEC 1
J 0
(2800 2000);
DISPLAY 1.021277 (2800 2000);
DISPLAY INVISIBLE (2800 2000);
FORCEADD Q_CAPP..1
(3150 1825);
FORCEPROP 1 LAST PART_NUMBER CC72703MD38
J 0
(3200 1650);
DISPLAY 0.617021 (3200 1650);
PAINT BLUE (3200 1650);
DISPLAY INVISIBLE (3200 1650);
FORCEPROP 1 LAST MATERIAL OSCON
J 0
(3200 1750);
DISPLAY 0.617021 (3200 1750);
PAINT SKYBLUE (3200 1750);
FORCEPROP 1 LAST VALUE 270UF
J 0
(3200 1900);
DISPLAY 0.617021 (3200 1900);
PAINT SKYBLUE (3200 1900);
FORCEPROP 1 LAST TOLERANCE 20%
J 0
(3200 1850);
DISPLAY 0.617021 (3200 1850);
PAINT SKYBLUE (3200 1850);
FORCEPROP 1 LAST PACK_TYPE THLF
J 0
(3200 1700);
DISPLAY 0.617021 (3200 1700);
PAINT SKYBLUE (3200 1700);
FORCEPROP 1 LAST VOLTAGE 16V
J 0
(3200 1800);
DISPLAY 0.617021 (3200 1800);
PAINT SKYBLUE (3200 1800);
FORCEPROP 1 LAST LOCATION PC321
J 0
(3200 1950);
DISPLAY 0.617021 (3200 1950);
PAINT AQUA (3200 1950);
FORCEPROP 1 LASTPIN (3150 1925) $PN 1
J 0
(3160 1910);
DISPLAY 0.617021 (3160 1910);
PAINT MONO (3160 1910);
FORCEPROP 1 LASTPIN (3150 1725) $PN 2
J 0
(3160 1710);
DISPLAY 0.617021 (3160 1710);
PAINT MONO (3160 1710);
FORCEPROP 2 LAST CDS_LIB pure_quanta
J 0
(3150 1825);
DISPLAY INVISIBLE (3150 1825);
FORCEPROP 1 LAST PATH I93
J 0
(3200 1975);
DISPLAY 0.978723 (3200 1975);
DISPLAY INVISIBLE (3200 1975);
FORCEPROP 1 LAST LOCATION PC321
J 0
(3200 2000);
DISPLAY 1.021277 (3200 2000);
PAINT AQUA (3200 2000);
DISPLAY INVISIBLE (3200 2000);
FORCEPROP 0 LAST $SEC 1
J 0
(3200 2000);
DISPLAY 0.680851 (3200 2000);
PAINT MONO (3200 2000);
DISPLAY INVISIBLE (3200 2000);
FORCEPROP 0 LAST CDS_SEC 1
J 0
(3200 2000);
DISPLAY 1.021277 (3200 2000);
DISPLAY INVISIBLE (3200 2000);
FORCEADD Q_CAPP..1
(3550 1825);
FORCEPROP 1 LAST PART_NUMBER CC72703MD38
J 0
(3600 1650);
DISPLAY 0.617021 (3600 1650);
PAINT BLUE (3600 1650);
DISPLAY INVISIBLE (3600 1650);
FORCEPROP 1 LAST VOLTAGE 16V
J 0
(3600 1800);
DISPLAY 0.617021 (3600 1800);
PAINT SKYBLUE (3600 1800);
FORCEPROP 1 LAST TOLERANCE 20%
J 0
(3600 1850);
DISPLAY 0.617021 (3600 1850);
PAINT SKYBLUE (3600 1850);
FORCEPROP 1 LAST MATERIAL OSCON
J 0
(3600 1750);
DISPLAY 0.617021 (3600 1750);
PAINT SKYBLUE (3600 1750);
FORCEPROP 1 LAST VALUE 270UF
J 0
(3600 1900);
DISPLAY 0.617021 (3600 1900);
PAINT SKYBLUE (3600 1900);
FORCEPROP 1 LAST PACK_TYPE THLF
J 0
(3600 1700);
DISPLAY 0.617021 (3600 1700);
PAINT SKYBLUE (3600 1700);
FORCEPROP 1 LAST LOCATION PC324
J 0
(3600 1950);
DISPLAY 0.617021 (3600 1950);
PAINT AQUA (3600 1950);
FORCEPROP 1 LASTPIN (3550 1925) $PN 1
J 0
(3560 1910);
DISPLAY 0.617021 (3560 1910);
PAINT MONO (3560 1910);
FORCEPROP 1 LASTPIN (3550 1725) $PN 2
J 0
(3560 1710);
DISPLAY 0.617021 (3560 1710);
PAINT MONO (3560 1710);
FORCEPROP 2 LAST CDS_LIB pure_quanta
J 0
(3550 1825);
DISPLAY INVISIBLE (3550 1825);
FORCEPROP 1 LAST PATH I94
J 0
(3600 1975);
DISPLAY 0.978723 (3600 1975);
DISPLAY INVISIBLE (3600 1975);
FORCEPROP 1 LAST LOCATION PC324
J 0
(3600 2000);
DISPLAY 1.021277 (3600 2000);
PAINT AQUA (3600 2000);
DISPLAY INVISIBLE (3600 2000);
FORCEPROP 0 LAST $SEC 1
J 0
(3600 2000);
DISPLAY 0.680851 (3600 2000);
PAINT MONO (3600 2000);
DISPLAY INVISIBLE (3600 2000);
FORCEPROP 0 LAST CDS_SEC 1
J 0
(3600 2000);
DISPLAY 1.021277 (3600 2000);
DISPLAY INVISIBLE (3600 2000);
FORCEADD Q_CAPP..1
(3950 1825);
FORCEPROP 1 LAST PART_NUMBER CC72703MD38
J 0
(4000 1650);
DISPLAY 0.638298 (4000 1650);
PAINT BLUE (4000 1650);
DISPLAY INVISIBLE (4000 1650);
FORCEPROP 1 LAST PACK_TYPE THLF
J 0
(4000 1700);
DISPLAY 0.638298 (4000 1700);
PAINT SKYBLUE (4000 1700);
FORCEPROP 1 LAST TOLERANCE 20%
J 0
(4000 1850);
DISPLAY 0.638298 (4000 1850);
PAINT SKYBLUE (4000 1850);
FORCEPROP 1 LAST VOLTAGE 16V
J 0
(4000 1800);
DISPLAY 0.638298 (4000 1800);
PAINT SKYBLUE (4000 1800);
FORCEPROP 1 LAST MATERIAL OSCON
J 0
(4000 1750);
DISPLAY 0.638298 (4000 1750);
PAINT SKYBLUE (4000 1750);
FORCEPROP 1 LAST VALUE 270UF
J 0
(4000 1900);
DISPLAY 0.638298 (4000 1900);
PAINT SKYBLUE (4000 1900);
FORCEPROP 1 LAST LOCATION PC2345
J 0
(4000 1950);
DISPLAY 0.638298 (4000 1950);
PAINT AQUA (4000 1950);
FORCEPROP 1 LASTPIN (3950 1925) $PN 1
J 0
(3960 1910);
DISPLAY 0.787234 (3960 1910);
PAINT MONO (3960 1910);
FORCEPROP 1 LASTPIN (3950 1725) $PN 2
J 0
(3960 1710);
DISPLAY 0.787234 (3960 1710);
PAINT MONO (3960 1710);
FORCEPROP 2 LAST CDS_LIB pure_quanta
J 0
(3950 1825);
DISPLAY INVISIBLE (3950 1825);
FORCEPROP 1 LAST PATH I95
J 0
(4000 1975);
DISPLAY 0.978723 (4000 1975);
DISPLAY INVISIBLE (4000 1975);
FORCEPROP 0 LAST $SEC 1
J 0
(4000 2000);
DISPLAY 0.680851 (4000 2000);
PAINT MONO (4000 2000);
DISPLAY INVISIBLE (4000 2000);
FORCEPROP 0 LAST CDS_SEC 1
J 0
(4000 2000);
DISPLAY 1.021277 (4000 2000);
DISPLAY INVISIBLE (4000 2000);
FORCEADD VCC15..1
(3950 2150);
FORCEPROP 3 LASTPIN (3950 2100) SIG_NAME SW_P12V_PVCCIN_CPU0_FLT\g
J 0
(3960 2110);
DISPLAY 0.659574 (3960 2110);
PAINT MONO (3960 2110);
DISPLAY INVISIBLE (3960 2110);
FORCEPROP 1 LAST HDL_POWER SW_P12V_PVCCIN_CPU0_FLT
J 1
(4000 2200);
DISPLAY 0.617021 (4000 2200);
PAINT GREEN (4000 2200);
FORCEPROP 2 LAST CDS_LIB logical_power
J 0
(3950 2150);
DISPLAY INVISIBLE (3950 2150);
FORCEPROP 1 LAST PATH I96
J 0
(4000 2175);
DISPLAY 0.872340 (4000 2175);
PAINT AQUA (4000 2175);
DISPLAY INVISIBLE (4000 2175);
FORCEADD Q_RES..1
(-1000 1150);
FORCEPROP 1 LAST PART_NUMBER CS-3302FB01
J 0
(-1100 1200);
DISPLAY 0.617021 (-1100 1200);
PAINT BLUE (-1100 1200);
DISPLAY INVISIBLE (-1100 1200);
FORCEPROP 1 LAST VALUE 3.3
J 2
(-775 1150);
DISPLAY 0.617021 (-775 1150);
PAINT SKYBLUE (-775 1150);
FORCEPROP 1 LAST WATTAGE 1/16W
J 2
(-750 1225);
DISPLAY 0.617021 (-750 1225);
PAINT SKYBLUE (-750 1225);
FORCEPROP 1 LAST TOLERANCE 1%
J 0
(-750 1150);
DISPLAY 0.617021 (-750 1150);
PAINT SKYBLUE (-750 1150);
FORCEPROP 1 LAST MATERIAL CHIP
J 0
(-1100 1250);
DISPLAY 0.617021 (-1100 1250);
PAINT SKYBLUE (-1100 1250);
FORCEPROP 1 LAST PACK_TYPE 0402LF
J 0
(-1100 1225);
DISPLAY 0.617021 (-1100 1225);
PAINT SKYBLUE (-1100 1225);
FORCEPROP 1 LAST LOCATION PR1787
J 0
(-1250 1150);
DISPLAY 0.617021 (-1250 1150);
PAINT AQUA (-1250 1150);
FORCEPROP 1 LASTPIN (-1100 1150) $PN 1
J 0
(-1088 1162);
DISPLAY 0.617021 (-1088 1162);
FORCEPROP 1 LASTPIN (-900 1150) $PN 2
J 0
(-938 1162);
DISPLAY 0.617021 (-938 1162);
FORCEPROP 2 LAST CDS_LIB pure_quanta
J 0
(-1000 1150);
PAINT MONO (-1000 1150);
DISPLAY INVISIBLE (-1000 1150);
FORCEPROP 1 LAST PATH I97
J 0
(-1050 1300);
DISPLAY 0.978723 (-1050 1300);
PAINT WHITE (-1050 1300);
DISPLAY INVISIBLE (-1050 1300);
FORCEPROP 2 LAST $SEC 1
J 0
(-1050 1350);
DISPLAY 0.680851 (-1050 1350);
PAINT MONO (-1050 1350);
DISPLAY INVISIBLE (-1050 1350);
FORCEPROP 2 LAST CDS_SEC 1
J 0
(-1050 1350);
DISPLAY 1.021277 (-1050 1350);
DISPLAY INVISIBLE (-1050 1350);
FORCEADD QUANTA_TITLE_BLOCK_C..1
(4575 -3650);
FORCEPROP 0 LAST CDS_CON_LAST_MODIFIED Fri Aug 25 14:04:37 2023
J 0
(2690 -3635);
DISPLAY INVISIBLE (2690 -3635);
FORCEPROP 1 LAST CUSTOM_TXT_CDS <CON_LAST_MODIFIED>
J 0
(2690 -3635);
DISPLAY 0.978723 (2690 -3635);
FORCEPROP 2 LAST CUSTOM_TXT_CDS <XR_PAGE_TITLE>
J 0
(-3315 1600);
DISPLAY 0.638298 (-3315 1600);
PAINT PINK (-3315 1600);
DISPLAY INVISIBLE (-3315 1600);
FORCEPROP 1 LAST CUSTOM_TXT_CDS <NAME_2>
J 0
(1400 -3600);
FORCEPROP 1 LAST CUSTOM_TXT_CDS <NAME_1>
J 0
(1400 -3475);
FORCEPROP 1 LAST CUSTOM_TXT_CDS <Q_NUMBER>
J 0
(3172 -3547);
DISPLAY 1.212766 (3172 -3547);
FORCEPROP 1 LAST CUSTOM_TXT_CDS <Q_PROJ>
J 0
(2193 -3548);
DISPLAY 1.212766 (2193 -3548);
FORCEPROP 1 LAST CUSTOM_TXT_CDS <Q_REV>
J 0
(4391 -3547);
DISPLAY 1.212766 (4391 -3547);
FORCEPROP 1 LAST CUSTOM_TXT_CDS <CON_PAGE_NUM> OF <CON_TOTAL_PAGES>
J 0
(4129 -3632);
DISPLAY 0.978723 (4129 -3632);
FORCEPROP 1 LAST Q_TITLE VCCIN CPU0 VR PHASE 1&2 (2/7)
J 0
(-4700 -3600);
DISPLAY 2.446809 (-4700 -3600);
PAINT GREEN (-4700 -3600);
FORCEPROP 1 LAST Q_DEPT 
J 1
(812 -3601);
DISPLAY 1.957447 (812 -3601);
PAINT GREEN (812 -3601);
FORCEPROP 2 LAST CDS_XR_PAGE_TITLE CR-267 : @S9S_MB_2U_LIB.S9S_MB_2U(SCH_1):PAGE267
J 0
(-3315 1600);
DISPLAY 0.638298 (-3315 1600);
PAINT PINK (-3315 1600);
DISPLAY INVISIBLE (-3315 1600);
FORCEPROP 2 LAST CDS_LIB pure_quanta
J 0
(4575 -3650);
DISPLAY INVISIBLE (4575 -3650);
FORCEPROP 1 LAST CDS_LMAN_SYM_OUTLINE -9475,6775,100,-125
J 0
(4575 -3650);
DISPLAY 0.468085 (4575 -3650);
PAINT GREEN (4575 -3650);
DISPLAY INVISIBLE (4575 -3650);
FORCEPROP 2 LAST PAGE_BORDER TRUE
J 0
(-3315 1600);
DISPLAY 0.638298 (-3315 1600);
PAINT PINK (-3315 1600);
DISPLAY INVISIBLE (-3315 1600);
FORCEPROP 1 LAST COMMENT_BODY TRUE
J 0
(4587 -3663);
DISPLAY 0.978723 (4587 -3663);
PAINT GREEN (4587 -3663);
DISPLAY INVISIBLE (4587 -3663);
FORCEADD DNS..1
(-4200 -2650);
PAINT RED (-4200 -2650);
FORCEPROP 1 LAST COMMENT_BODY TRUE
R 1
J 0
(-4125 -2875);
DISPLAY 0.872340 (-4125 -2875);
PAINT GREEN (-4125 -2875);
DISPLAY INVISIBLE (-4125 -2875);
FORCEPROP 2 LAST CDS_LIB mstr_misc
J 0
(-4200 -2650);
PAINT MONO (-4200 -2650);
DISPLAY INVISIBLE (-4200 -2650);
FORCEADD DNS..1
(-4175 175);
PAINT RED (-4175 175);
FORCEPROP 1 LAST COMMENT_BODY TRUE
R 1
J 0
(-4100 -50);
DISPLAY 0.872340 (-4100 -50);
PAINT GREEN (-4100 -50);
DISPLAY INVISIBLE (-4100 -50);
FORCEPROP 2 LAST CDS_LIB mstr_misc
J 0
(-4175 175);
PAINT MONO (-4175 175);
DISPLAY INVISIBLE (-4175 175);
FORCEADD DNS..1
(-3625 2350);
PAINT RED (-3625 2350);
FORCEPROP 1 LAST COMMENT_BODY TRUE
R 1
J 0
(-3550 2125);
DISPLAY 0.872340 (-3550 2125);
PAINT GREEN (-3550 2125);
DISPLAY INVISIBLE (-3550 2125);
FORCEPROP 2 LAST CDS_LIB mstr_misc
J 0
(-3625 2350);
DISPLAY INVISIBLE (-3625 2350);
FORCEADD DNS..1
(2550 -1400);
PAINT RED (2550 -1400);
FORCEPROP 1 LAST COMMENT_BODY TRUE
R 1
J 0
(2625 -1625);
DISPLAY 0.872340 (2625 -1625);
PAINT GREEN (2625 -1625);
DISPLAY INVISIBLE (2625 -1625);
FORCEPROP 2 LAST CDS_LIB mstr_misc
J 0
(2550 -1400);
DISPLAY INVISIBLE (2550 -1400);
FORCEADD DNS..1
(3025 -1425);
PAINT RED (3025 -1425);
FORCEPROP 1 LAST COMMENT_BODY TRUE
R 1
J 0
(3100 -1650);
DISPLAY 0.872340 (3100 -1650);
PAINT GREEN (3100 -1650);
DISPLAY INVISIBLE (3100 -1650);
FORCEPROP 2 LAST CDS_LIB mstr_misc
J 0
(3025 -1425);
DISPLAY INVISIBLE (3025 -1425);
FORCEADD DNS..1
(3500 -1425);
PAINT RED (3500 -1425);
FORCEPROP 1 LAST COMMENT_BODY TRUE
R 1
J 0
(3575 -1650);
DISPLAY 0.872340 (3575 -1650);
PAINT GREEN (3575 -1650);
DISPLAY INVISIBLE (3575 -1650);
FORCEPROP 2 LAST CDS_LIB mstr_misc
J 0
(3500 -1425);
DISPLAY INVISIBLE (3500 -1425);
FORCEADD DNS..1
(3975 -1450);
PAINT RED (3975 -1450);
FORCEPROP 1 LAST COMMENT_BODY TRUE
R 1
J 0
(4050 -1675);
DISPLAY 0.872340 (4050 -1675);
PAINT GREEN (4050 -1675);
DISPLAY INVISIBLE (4050 -1675);
FORCEPROP 2 LAST CDS_LIB mstr_misc
J 0
(3975 -1450);
DISPLAY INVISIBLE (3975 -1450);
FORCEADD DNS..1
(1925 1900);
PAINT RED (1925 1900);
FORCEPROP 1 LAST COMMENT_BODY TRUE
R 1
J 0
(2000 1675);
DISPLAY 0.872340 (2000 1675);
PAINT GREEN (2000 1675);
DISPLAY INVISIBLE (2000 1675);
FORCEPROP 2 LAST CDS_LIB mstr_misc
J 0
(1925 1900);
DISPLAY INVISIBLE (1925 1900);
WIRE 16 -1 (-3800 -900)(-3800 -850);
WIRE 16 -1 (-3375 -900)(-3800 -900);
WIRE 16 -1 (-3800 -1025)(-3800 -900);
WIRE 16 -1 (-4325 2550)(-4325 2475);
WIRE 16 -1 (-3675 2550)(-3675 2475);
WIRE 16 -1 (325 -900)(325 -975);
WIRE 16 -1 (3975 -1150)(3975 -1200);
WIRE 16 -1 (4025 -2125)(4025 -2250);
WIRE 16 -1 (350 1925)(350 1850);
WIRE 16 -1 (1450 2150)(1450 2025);
WIRE 16 -1 (3975 -275)(3975 -325);
WIRE 16 -1 (3525 850)(3525 700);
WIRE 16 -1 (3950 2100)(3950 2025);
WIRE 16 -1 (-4200 -2725)(-4200 -2800);
WIRE 16 -1 (-4300 -2325)(-4300 -2350);
WIRE 16 -1 (-4300 -2325)(-3575 -2325);
WIRE 16 -1 (-3800 -1725)(-3800 -1825);
WIRE 16 -1 (-3375 -1225)(-3375 -1300);
WIRE 16 -1 (-1625 -2725)(-1625 -2800);
WIRE 16 -1 (-1625 -2675)(-1625 -2725);
WIRE 16 -1 (-1875 -2725)(-1625 -2725);
WIRE 16 -1 (-4275 500)(-4275 450);
WIRE 16 -1 (-4275 500)(-3550 500);
WIRE 16 -1 (-4175 100)(-4175 25);
WIRE 16 -1 (-3775 1100)(-3775 1000);
WIRE 16 -1 (-3350 1600)(-3350 1525);
WIRE 16 -1 (-1600 100)(-1600 25);
WIRE 16 -1 (-1600 150)(-1600 100);
WIRE 16 -1 (-1850 100)(-1600 100);
WIRE 16 -1 (325 -1600)(325 -1475);
WIRE 16 -1 (3975 -1700)(3975 -1625);
WIRE 16 -1 (3975 -825)(3975 -750);
WIRE 16 -1 (4025 -2825)(4025 -2675);
WIRE 16 -1 (350 1225)(350 1350);
WIRE 16 -1 (1450 1625)(1450 1725);
WIRE 16 -1 (3525 175)(3525 275);
WIRE 16 -1 (3950 1550)(3950 1625);
WIRE 17 273 (1725 -25)(4425 -25);
WIRE 17 273 (4425 -25)(4425 -1900);
WIRE 17 273 (1725 -1900)(1725 -25);
WIRE 17 273 (1725 -1900)(4425 -1900);
WIRE 16 -1 (3975 -650)(3975 -750);
WIRE 16 -1 (1950 -750)(1950 -625);
WIRE 16 -1 (3475 -650)(3475 -750);
WIRE 16 -1 (3975 -750)(3475 -750);
WIRE 16 -1 (2950 -750)(2950 -650);
WIRE 16 -1 (2950 -750)(3475 -750);
WIRE 16 -1 (2425 -750)(1950 -750);
WIRE 16 -1 (2425 -650)(2425 -750);
WIRE 16 -1 (2425 -750)(2950 -750);
WIRE 16 -1 (3975 -450)(3975 -325);
WIRE 16 -1 (3475 -450)(3475 -325);
WIRE 16 -1 (3975 -325)(3475 -325);
WIRE 16 -1 (2950 -325)(2950 -450);
WIRE 16 -1 (2950 -325)(3475 -325);
WIRE 16 -1 (2425 -450)(2425 -325);
WIRE 16 -1 (2425 -325)(2950 -325);
WIRE 16 -1 (1950 -325)(2425 -325);
WIRE 16 -1 (1950 -425)(1950 -325);
WIRE 16 -1 (3975 -1525)(3975 -1625);
WIRE 16 -1 (3475 -1525)(3475 -1625);
WIRE 16 -1 (3975 -1625)(3475 -1625);
WIRE 16 -1 (3025 -1500)(3025 -1625);
WIRE 16 -1 (3025 -1625)(3475 -1625);
WIRE 16 -1 (3025 -1625)(2525 -1625);
WIRE 16 -1 (2525 -1525)(2525 -1625);
WIRE 16 -1 (3975 -1325)(3975 -1200);
WIRE 16 -1 (3475 -1325)(3475 -1200);
WIRE 16 -1 (3975 -1200)(3475 -1200);
WIRE 16 -1 (3025 -1300)(3025 -1200);
WIRE 16 -1 (3025 -1200)(3475 -1200);
WIRE 16 -1 (3025 -1200)(2525 -1200);
WIRE 16 -1 (2525 -1325)(2525 -1200);
WIRE 16 -1 (3950 1725)(3950 1625);
WIRE 16 -1 (3550 1725)(3550 1625);
WIRE 16 -1 (3550 1625)(3950 1625);
WIRE 16 -1 (3150 1725)(3150 1625);
WIRE 16 -1 (3150 1625)(3550 1625);
WIRE 16 -1 (2750 1725)(2750 1625);
WIRE 16 -1 (3150 1625)(2750 1625);
WIRE 16 -1 (2350 1625)(2750 1625);
WIRE 16 -1 (2350 1725)(2350 1625);
WIRE 16 -1 (3950 2025)(3950 1925);
WIRE 16 -1 (3550 1925)(3550 2025);
WIRE 16 -1 (3550 2025)(3950 2025);
WIRE 16 -1 (2275 1900)(1975 1900);
WIRE 16 -1 (2275 2025)(1975 2025);
WIRE 16 -1 (2275 2025)(2275 1900);
WIRE 16 -1 (3150 1925)(3150 2025);
WIRE 16 -1 (3150 2025)(3550 2025);
WIRE 16 -1 (2750 1925)(2750 2025);
WIRE 16 -1 (3150 2025)(2750 2025);
WIRE 16 -1 (2350 2025)(2275 2025);
WIRE 16 -1 (2350 2025)(2350 1925);
WIRE 16 -1 (2350 2025)(2750 2025);
WIRE 16 -1 (3225 600)(3225 700);
WIRE 16 -1 (3525 700)(3225 700);
WIRE 16 -1 (1725 100)(200 100);
WIRE 16 -1 (1725 700)(575 700);
WIRE 16 -1 (1725 700)(1725 100);
WIRE 16 -1 (2800 700)(2800 600);
WIRE 16 -1 (2800 700)(3225 700);
WIRE 16 -1 (2375 600)(2375 700);
WIRE 16 -1 (2375 700)(2800 700);
WIRE 16 -1 (1975 700)(1725 700);
WIRE 16 -1 (1975 600)(1975 700);
WIRE 16 -1 (1975 700)(2375 700);
WIRE 16 -1 (3225 400)(3225 275);
WIRE 16 -1 (3525 275)(3225 275);
WIRE 16 -1 (2800 275)(2800 400);
WIRE 16 -1 (3225 275)(2800 275);
WIRE 16 -1 (2375 400)(2375 275);
WIRE 16 -1 (2375 275)(2800 275);
WIRE 16 -1 (1975 275)(2375 275);
WIRE 16 -1 (1975 400)(1975 275);
WIRE 16 -1 (1575 1900)(1775 1900);
WIRE 16 -1 (1575 2025)(1575 1900);
WIRE 16 -1 (1575 2025)(1775 2025);
WIRE 16 -1 (1450 2025)(1575 2025);
WIRE 16 -1 (1450 1925)(1450 2025);
WIRE 16 -1 (200 1700)(200 1850);
WIRE 16 -1 (350 1850)(200 1850);
WIRE 16 -1 (-175 1700)(-175 1850);
WIRE 16 -1 (200 1850)(-175 1850);
WIRE 16 -1 (-575 1850)(-575 1700);
WIRE 16 -1 (-175 1850)(-575 1850);
WIRE 16 -1 (-975 1700)(-975 1850);
WIRE 16 -1 (-575 1850)(-975 1850);
WIRE 16 -1 (-1375 1700)(-1375 1850);
WIRE 16 -1 (-975 1850)(-1375 1850);
WIRE 16 -1 (-1675 1850)(-1375 1850);
WIRE 16 -1 (-1850 1350)(-1675 1350);
WIRE 16 -1 (-1675 1850)(-1675 1350);
WIRE 16 -1 (-1675 1300)(-1675 1350);
WIRE 16 -1 (-1850 1300)(-1675 1300);
WIRE 16 -1 (575 450)(1075 450);
FORCEPROP 2 LAST SIG_NAME IND_P0_CPL2
J 0
(665 460);
DISPLAY 0.617021 (665 460);
WIRE 16 -1 (200 1500)(200 1350);
WIRE 16 -1 (350 1350)(200 1350);
WIRE 16 -1 (-175 1500)(-175 1350);
WIRE 16 -1 (200 1350)(-175 1350);
WIRE 16 -1 (-575 1500)(-575 1350);
WIRE 16 -1 (-175 1350)(-575 1350);
WIRE 16 -1 (-975 1500)(-975 1350);
WIRE 16 -1 (-575 1350)(-975 1350);
WIRE 16 -1 (-975 1350)(-1375 1350);
WIRE 16 -1 (-1375 1500)(-1375 1350);
WIRE 16 -1 (2900 -2675)(2900 -2550);
WIRE 16 -1 (3325 -2675)(2900 -2675);
WIRE 16 -1 (3325 -2675)(3325 -2550);
WIRE 16 -1 (3725 -2675)(3325 -2675);
WIRE 16 -1 (4025 -2675)(3725 -2675);
WIRE 16 -1 (3725 -2550)(3725 -2675);
WIRE 16 -1 (3725 -2250)(3725 -2350);
WIRE 16 -1 (3725 -2250)(4025 -2250);
WIRE 16 -1 (3325 -2250)(3325 -2350);
WIRE 16 -1 (3325 -2250)(3725 -2250);
WIRE 16 -1 (2900 -2250)(2900 -2350);
WIRE 16 -1 (2900 -2250)(3325 -2250);
WIRE 16 -1 (125 -2675)(1875 -2675);
WIRE 16 -1 (1875 -2250)(1875 -2675);
WIRE 16 -1 (2900 -2250)(1875 -2250);
WIRE 16 -1 (1875 -2125)(1875 -2250);
WIRE 16 -1 (650 -2125)(1875 -2125);
WIRE 16 -1 (650 -2375)(1150 -2375);
FORCEPROP 2 LAST SIG_NAME IND_P0_CPL3
J 0
(740 -2365);
DISPLAY 0.617021 (740 -2365);
WIRE 16 -1 (100 -1125)(100 -975);
WIRE 16 -1 (325 -975)(100 -975);
WIRE 16 -1 (-275 -1125)(-275 -975);
WIRE 16 -1 (-275 -975)(100 -975);
WIRE 16 -1 (-675 -975)(-675 -1125);
WIRE 16 -1 (-675 -975)(-275 -975);
WIRE 16 -1 (-1075 -1125)(-1075 -975);
WIRE 16 -1 (-1075 -975)(-675 -975);
WIRE 16 -1 (-1475 -1125)(-1475 -975);
WIRE 16 -1 (-1475 -975)(-1075 -975);
WIRE 16 -1 (-1700 -975)(-1475 -975);
WIRE 16 -1 (-1875 -1475)(-1700 -1475);
WIRE 16 -1 (-1700 -975)(-1700 -1475);
WIRE 16 -1 (-1700 -1525)(-1700 -1475);
WIRE 16 -1 (-1875 -1525)(-1700 -1525);
WIRE 16 -1 (100 -1325)(100 -1475);
WIRE 16 -1 (325 -1475)(100 -1475);
WIRE 16 -1 (-275 -1325)(-275 -1475);
WIRE 16 -1 (-275 -1475)(100 -1475);
WIRE 16 -1 (-675 -1325)(-675 -1475);
WIRE 16 -1 (-675 -1475)(-275 -1475);
WIRE 16 -1 (-1075 -1325)(-1075 -1475);
WIRE 16 -1 (-675 -1475)(-1075 -1475);
WIRE 16 -1 (-1475 -1475)(-1075 -1475);
WIRE 16 -1 (-1475 -1325)(-1475 -1475);
WIRE 16 -1 (-275 1150)(-275 1075);
WIRE 16 -1 (-900 1150)(-275 1150);
FORCEPROP 2 LAST SIG_NAME SW_PVCCIN_CPU0_BOOT1_R
J 0
(-635 1160);
DISPLAY 0.617021 (-635 1160);
WIRE 16 -1 (-800 450)(-225 450);
FORCEPROP 2 LAST SIG_NAME IND_P0_CPL1
J 0
(-735 460);
DISPLAY 0.617021 (-735 460);
WIRE 16 -1 (-275 800)(-275 875);
WIRE 16 -1 (-1850 800)(-275 800);
FORCEPROP 2 LAST SIG_NAME SW_PVCCIN_CPU0_BOOTR1
J 0
(-1660 810);
DISPLAY 0.617021 (-1660 810);
WIRE 16 -1 (-1850 700)(-225 700);
FORCEPROP 2 LAST SIG_NAME SW_PVCCIN_CPU0_SW1
J 0
(-1660 710);
DISPLAY 0.617021 (-1660 710);
WIRE 16 -1 (-1700 1150)(-1100 1150);
WIRE 16 -1 (-1700 1050)(-1700 1150);
FORCEPROP 2 LAST SIG_NAME SW_PVCCIN_CPU0_BOOT1
J 0
(-1860 1160);
DISPLAY 0.617021 (-1860 1160);
WIRE 16 -1 (-1850 1050)(-1700 1050);
WIRE 16 -1 (0 100)(-1500 100);
FORCEPROP 2 LAST SIG_NAME PVCCIN_CPU0_VOS1
J 0
(-1285 110);
DISPLAY 0.617021 (-1285 110);
WIRE 16 -1 (-1500 450)(-1500 100);
WIRE 16 -1 (-1850 450)(-1500 450);
WIRE 16 -1 (-1850 150)(-1600 150);
WIRE 16 -1 (-1850 200)(-1600 200);
WIRE 16 -1 (-1600 200)(-1600 150);
WIRE 16 -1 (-1600 250)(-1600 200);
WIRE 16 -1 (-1850 250)(-1600 250);
WIRE 16 -1 (-2700 1350)(-2775 1350);
WIRE 16 -1 (-2775 1350)(-2775 1925);
WIRE 16 -1 (-3350 1925)(-3350 1800);
WIRE 16 -1 (-2775 1925)(-3350 1925);
WIRE 16 -1 (-3350 1925)(-3675 1925);
FORCEPROP 2 LAST SIG_NAME PVCCIN_CPU0_PVCC
J 0
(-3560 1935);
DISPLAY 0.617021 (-3560 1935);
WIRE 16 -1 (-3675 2275)(-3675 1925);
WIRE 16 -1 (-3775 1800)(-3775 1925);
WIRE 16 -1 (-3675 1925)(-3775 1925);
WIRE 16 -1 (-4325 1925)(-3775 1925);
WIRE 16 -1 (-4325 2275)(-4325 1925);
WIRE 16 -1 (-2700 850)(-2800 850);
WIRE 16 -1 (-2800 850)(-2800 1050);
WIRE 16 -1 (-2800 1050)(-2700 1050);
WIRE 16 -1 (-3375 1050)(-2800 1050);
FORCEPROP 2 LAST SIG_NAME PVCCIN_CPU0_VDD1
J 0
(-3335 1060);
DISPLAY 0.617021 (-3335 1060);
WIRE 16 -1 (-3375 1050)(-3375 1450);
WIRE 16 -1 (-3775 1450)(-3775 1300);
WIRE 16 -1 (-3775 1600)(-3775 1450);
WIRE 16 -1 (-3775 1450)(-3375 1450);
WIRE 16 -1 (-2700 700)(-3550 700);
FORCEPROP 2 LAST SIG_NAME PVCCIN_CPU0_IMON1
J 0
(-3510 710);
DISPLAY 0.617021 (-3510 710);
WIRE 16 -1 (-2700 100)(-3550 100);
FORCEPROP 2 LAST SIG_NAME PVCCIN_CPU0_PWM1
J 0
(-3510 110);
DISPLAY 0.617021 (-3510 110);
WIRE 16 -1 (-2700 200)(-3550 200);
FORCEPROP 2 LAST SIG_NAME PVCCIN_CPU0_ATSEN
J 0
(-3510 210);
DISPLAY 0.617021 (-3510 210);
WIRE 16 -1 (-2800 500)(-3350 500);
WIRE 16 -1 (-3550 600)(-2800 600);
FORCEPROP 2 LAST SIG_NAME PVCCIN_CPU0_VREF
J 0
(-3510 610);
DISPLAY 0.617021 (-3510 610);
WIRE 16 -1 (-2800 600)(-2800 500);
FORCEPROP 0 LAST CDS_PHYS_NET_NAME PVCCIN_CPU0_VREF
J 0
(-2800 525);
PAINT MONO (-2800 525);
DISPLAY INVISIBLE (-2800 525);
WIRE 16 -1 (-2800 600)(-2700 600);
WIRE 16 -1 (-4175 400)(-4175 300);
WIRE 16 -1 (-4175 400)(-2700 400);
FORCEPROP 2 LAST SIG_NAME PVCCIN_CPU0_LSET1
J 0
(-3510 410);
DISPLAY 0.617021 (-3510 410);
WIRE 16 -1 (-225 -1675)(-225 -1775);
WIRE 16 -1 (-925 -1675)(-225 -1675);
FORCEPROP 2 LAST SIG_NAME SW_PVCCIN_CPU0_BOOT2_R
J 0
(-685 -1665);
DISPLAY 0.617021 (-685 -1665);
WIRE 16 -1 (-700 -2375)(-150 -2375);
FORCEPROP 2 LAST SIG_NAME IND_P0_CPL2
J 0
(-635 -2365);
DISPLAY 0.617021 (-635 -2365);
WIRE 16 -1 (-1875 -2125)(-150 -2125);
FORCEPROP 2 LAST SIG_NAME SW_PVCCIN_CPU0_SW2
J 0
(-1685 -2115);
DISPLAY 0.617021 (-1685 -2115);
WIRE 16 -1 (-225 -2025)(-225 -1975);
WIRE 16 -1 (-1875 -2025)(-225 -2025);
FORCEPROP 2 LAST SIG_NAME SW_PVCCIN_CPU0_BOOTR2
J 0
(-1685 -2015);
DISPLAY 0.617021 (-1685 -2015);
WIRE 16 -1 (-1725 -1675)(-1125 -1675);
WIRE 16 -1 (-1725 -1775)(-1725 -1675);
FORCEPROP 2 LAST SIG_NAME SW_PVCCIN_CPU0_BOOT2
J 0
(-1885 -1665);
DISPLAY 0.617021 (-1885 -1665);
WIRE 16 -1 (-1875 -1775)(-1725 -1775);
WIRE 16 -1 (-1325 -2675)(-75 -2675);
FORCEPROP 2 LAST SIG_NAME PVCCIN_CPU0_VOS2
J 0
(-1185 -2665);
DISPLAY 0.617021 (-1185 -2665);
WIRE 16 -1 (-1325 -2375)(-1325 -2675);
WIRE 16 -1 (-1875 -2375)(-1325 -2375);
WIRE 16 -1 (-1875 -2575)(-1625 -2575);
WIRE 16 -1 (-1875 -2625)(-1625 -2625);
WIRE 16 -1 (-1625 -2575)(-1625 -2625);
WIRE 16 -1 (-1625 -2625)(-1625 -2675);
WIRE 16 -1 (-1875 -2675)(-1625 -2675);
WIRE 16 -1 (-3375 -900)(-3375 -1025);
WIRE 16 -1 (-2800 -900)(-3375 -900);
WIRE 16 -1 (-2800 -1475)(-2800 -900);
WIRE 16 -1 (-2725 -1475)(-2800 -1475);
WIRE 16 -1 (-2725 -1975)(-2825 -1975);
WIRE 16 -1 (-2825 -1975)(-2825 -1775);
WIRE 16 -1 (-2725 -1775)(-2825 -1775);
WIRE 16 -1 (-2825 -1775)(-3400 -1775);
FORCEPROP 2 LAST SIG_NAME PVCCIN_CPU0_VDD2
J 0
(-3360 -1765);
DISPLAY 0.617021 (-3360 -1765);
WIRE 16 -1 (-3400 -1775)(-3400 -1375);
WIRE 16 -1 (-3800 -1375)(-3800 -1525);
WIRE 16 -1 (-3800 -1225)(-3800 -1375);
WIRE 16 -1 (-3800 -1375)(-3400 -1375);
WIRE 16 -1 (-2725 -2125)(-3600 -2125);
FORCEPROP 2 LAST SIG_NAME PVCCIN_CPU0_IMON2
J 0
(-3560 -2115);
DISPLAY 0.617021 (-3560 -2115);
WIRE 16 -1 (-2825 -2325)(-3375 -2325);
WIRE 16 -1 (-3600 -2225)(-2825 -2225);
FORCEPROP 2 LAST SIG_NAME PVCCIN_CPU0_VREF
J 0
(-3560 -2215);
DISPLAY 0.617021 (-3560 -2215);
WIRE 16 -1 (-2825 -2225)(-2825 -2325);
FORCEPROP 0 LAST CDS_PHYS_NET_NAME PVCCIN_CPU0_VREF
J 0
(-2825 -2300);
PAINT MONO (-2825 -2300);
DISPLAY INVISIBLE (-2825 -2300);
WIRE 16 -1 (-2825 -2225)(-2725 -2225);
WIRE 16 -1 (-2725 -2625)(-3600 -2625);
FORCEPROP 2 LAST SIG_NAME PVCCIN_CPU0_ATSEN
J 0
(-3560 -2615);
DISPLAY 0.617021 (-3560 -2615);
WIRE 16 -1 (-2725 -2725)(-3600 -2725);
FORCEPROP 2 LAST SIG_NAME PVCCIN_CPU0_PWM2
J 0
(-3560 -2715);
DISPLAY 0.617021 (-3560 -2715);
WIRE 16 -1 (-4200 -2425)(-4200 -2525);
WIRE 16 -1 (-4200 -2425)(-2725 -2425);
FORCEPROP 2 LAST SIG_NAME PVCCIN_CPU0_LSET2
J 0
(-3560 -2415);
DISPLAY 0.617021 (-3560 -2415);
DOT 1 (-3800 -1375);
DOT 1 (-3800 -900);
DOT 1 (-3375 -900);
DOT 1 (-2825 -2225);
DOT 1 (-2825 -1775);
DOT 1 (-1625 -2725);
DOT 1 (-1625 -2675);
DOT 1 (-1625 -2625);
DOT 1 (-1700 -1475);
DOT 1 (-1475 -975);
DOT 1 (-1075 -1475);
DOT 1 (-675 -1475);
DOT 1 (-275 -1475);
DOT 1 (-1075 -975);
DOT 1 (-675 -975);
DOT 1 (-275 -975);
DOT 1 (-3775 1450);
DOT 1 (-2800 600);
DOT 1 (-2800 1050);
DOT 1 (-3775 1925);
DOT 1 (-3675 1925);
DOT 1 (-3350 1925);
DOT 1 (-1600 100);
DOT 1 (-1600 150);
DOT 1 (-1600 200);
DOT 1 (-1675 1350);
DOT 1 (-975 1350);
DOT 1 (-575 1350);
DOT 1 (-175 1350);
DOT 1 (-1375 1850);
DOT 1 (-975 1850);
DOT 1 (-575 1850);
DOT 1 (-175 1850);
DOT 1 (100 -1475);
DOT 1 (100 -975);
DOT 1 (1875 -2250);
DOT 1 (3325 -2675);
DOT 1 (3725 -2675);
DOT 1 (2900 -2250);
DOT 1 (2950 -750);
DOT 1 (3325 -2250);
DOT 1 (3025 -1625);
DOT 1 (3475 -1625);
DOT 1 (3725 -2250);
DOT 1 (3975 -1625);
DOT 1 (3025 -1200);
DOT 1 (3475 -1200);
DOT 1 (3475 -750);
DOT 1 (3975 -1200);
DOT 1 (3975 -750);
DOT 1 (200 1350);
DOT 1 (1725 700);
DOT 1 (200 1850);
DOT 1 (1450 2025);
DOT 1 (1575 2025);
DOT 1 (2425 -325);
DOT 1 (2375 275);
DOT 1 (2950 -325);
DOT 1 (2800 275);
DOT 1 (1975 700);
DOT 1 (2375 700);
DOT 1 (2800 700);
DOT 1 (2750 1625);
DOT 1 (3475 -325);
DOT 1 (3225 275);
DOT 1 (3975 -325);
DOT 1 (3225 700);
DOT 1 (3150 1625);
DOT 1 (3550 1625);
DOT 1 (3950 1625);
DOT 1 (2275 2025);
DOT 1 (2350 2025);
DOT 1 (2750 2025);
DOT 1 (3150 2025);
DOT 1 (3550 2025);
DOT 1 (3950 2025);
DOT 1 (2425 -750);
FORCENOTE
PVCCIN_CPU0_PHASE2
(-2650 -950) 0;
DISPLAY LEFT (-2650 -950);
DISPLAY 1.021277 (-2650 -950);
PAINT WHITE (-2650 -950);
FORCENOTE
PVCCIN_CPU0_PHASE1
(-2600 1875) 0;
DISPLAY LEFT (-2600 1875);
DISPLAY 1.021277 (-2600 1875);
PAINT WHITE (-2600 1875);
FORCENOTE
PGL6303.151HLT 
(550 -1675) 0;
DISPLAY LEFT (550 -1675);
DISPLAY 1.021277 (550 -1675);
FORCENOTE
11.0*7.5*12.5
(550 -1750) 0;
DISPLAY LEFT (550 -1750);
DISPLAY 1.021277 (550 -1750);
FORCENOTE
ISAT=70A@100C
(550 -1825) 0;
DISPLAY LEFT (550 -1825);
DISPLAY 1.021277 (550 -1825);
FORCENOTE
DCR=1-4,0.105M OHM
(550 -1900) 0;
DISPLAY LEFT (550 -1900);
DISPLAY 1.021277 (550 -1900);
FORCENOTE
DCR=2-3,0.27M OHM
(550 -1975) 0;
DISPLAY LEFT (550 -1975);
DISPLAY 1.021277 (550 -1975);
FORCENOTE
APPLY TO ALL RAILS.
(2650 -3150) 0;
DISPLAY LEFT (2650 -3150);
DISPLAY 1.021277 (2650 -3150);
FORCENOTE
RENESAS RECOMMEND BLEEDER RESISTOR
(2650 -3000) 0;
DISPLAY LEFT (2650 -3000);
DISPLAY 1.021277 (2650 -3000);
FORCENOTE
(499OHM) TO ABSORB LEAKAGE FROM SPS.
(2650 -3075) 0;
DISPLAY LEFT (2650 -3075);
DISPLAY 1.021277 (2650 -3075);
FORCENOTE
DCR=2-3,0.27M OHM
(500 850) 0;
DISPLAY LEFT (500 850);
DISPLAY 1.021277 (500 850);
FORCENOTE
PGL6303.151HLT 
(500 1150) 0;
DISPLAY LEFT (500 1150);
DISPLAY 1.021277 (500 1150);
FORCENOTE
11.0*7.5*12.5
(500 1075) 0;
DISPLAY LEFT (500 1075);
DISPLAY 1.021277 (500 1075);
FORCENOTE
ISAT=70A@100C
(500 1000) 0;
DISPLAY LEFT (500 1000);
DISPLAY 1.021277 (500 1000);
FORCENOTE
DCR=1-4,0.105M OHM
(500 925) 0;
DISPLAY LEFT (500 925);
DISPLAY 1.021277 (500 925);
FORCENOTE
ESR=9.5M OHM
(2375 1575) 0;
DISPLAY LEFT (2375 1575);
DISPLAY 0.638298 (2375 1575);
FORCENOTE
RESERVE BY ARCHER CITY
(2800 25) 0;
DISPLAY LEFT (2800 25);
DISPLAY 1.021277 (2800 25);
PAINT WHITE (2800 25);
FORCENOTE
ESR=9.5M OHM
(2775 1575) 0;
DISPLAY LEFT (2775 1575);
DISPLAY 0.638298 (2775 1575);
FORCENOTE
ESR=9.5M OHM
(3175 1575) 0;
DISPLAY LEFT (3175 1575);
DISPLAY 0.638298 (3175 1575);
FORCENOTE
ESR=9.5M OHM
(3575 1575) 0;
DISPLAY LEFT (3575 1575);
DISPLAY 0.638298 (3575 1575);
FORCENOTE
DCR = 0.04M OHM
(2300 2150) 0;
DISPLAY LEFT (2300 2150);
DISPLAY 0.808511 (2300 2150);
FORCENOTE
PGL6189.500HLT
(2300 2300) 0;
DISPLAY LEFT (2300 2300);
DISPLAY 0.808511 (2300 2300);
FORCENOTE
10.0*8.3*8.0
(2300 2250) 0;
DISPLAY LEFT (2300 2250);
DISPLAY 0.808511 (2300 2250);
FORCENOTE
ISAT = 120A @ 100C
(2300 2200) 0;
DISPLAY LEFT (2300 2200);
DISPLAY 0.808511 (2300 2200);
QUIT
